FILE_TYPE = MACRO_DRAWING;
SET COLOR_WIRE YELLOW;
SET COLOR_PROP ORANGE;
SET COLOR_DOT WHITE;
SET COLOR_ARC YELLOW;
SET COLOR_BODY GREEN;
SET COLOR_NOTE PURPLE;
SET PROP_DISPLAY VALUE;
SET PAGE_NUMBER P100;
FORCEADD OFFPAGE..2
R 2
(-3150 450);
FORCEPROP 2 LAST $XR0 100 
J 0
(-3405 450);
DISPLAY 0.638298 (-3405 450);
PAINT MONO (-3405 450);
FORCEPROP 2 LAST CDS_LIB standard
J 0
(-3150 450);
PAINT MONO (-3150 450);
DISPLAY INVISIBLE (-3150 450);
FORCEPROP 1 LAST OFFPAGE TRUE
J 2
(-3475 325);
DISPLAY 0.872340 (-3475 325);
DISPLAY INVISIBLE (-3475 325);
FORCEPROP 1 LAST COMMENT_BODY TRUE
J 2
(-3105 355);
DISPLAY 0.872340 (-3105 355);
PAINT GREEN (-3105 355);
DISPLAY INVISIBLE (-3105 355);
FORCEPROP 2 LAST PATH I1
J 0
(-3100 525);
DISPLAY 1.021277 (-3100 525);
DISPLAY INVISIBLE (-3100 525);
FORCEADD OFFPAGE..1
(-3150 2050);
FORCEPROP 2 LAST $XR1 101 
J 0
(-3491 2050);
DISPLAY 0.638298 (-3491 2050);
PAINT MONO (-3491 2050);
FORCEPROP 2 LAST $XR0 52 
J 0
(-3371 2050);
DISPLAY 0.638298 (-3371 2050);
PAINT MONO (-3371 2050);
FORCEPROP 2 LAST CDS_LIB standard
J 0
(-3150 2050);
PAINT MONO (-3150 2050);
DISPLAY INVISIBLE (-3150 2050);
FORCEPROP 1 LAST OFFPAGE TRUE
J 0
(-2825 1925);
DISPLAY 0.872340 (-2825 1925);
DISPLAY INVISIBLE (-2825 1925);
FORCEPROP 1 LAST COMMENT_BODY TRUE
J 0
(-3025 1950);
DISPLAY 0.872340 (-3025 1950);
PAINT GREEN (-3025 1950);
DISPLAY INVISIBLE (-3025 1950);
FORCEPROP 2 LAST PATH I10
J 0
(-3100 2125);
DISPLAY 1.021277 (-3100 2125);
DISPLAY INVISIBLE (-3100 2125);
FORCEADD TAP..1
(-575 3550);
FORCEPROP 3 LASTPIN (-625 3550) SIG_NAME M_B_CPU1_SA_DQ<14>
J 0
(-615 3560);
DISPLAY 0.659574 (-615 3560);
PAINT MONO (-615 3560);
DISPLAY INVISIBLE (-615 3560);
FORCEPROP 1 LASTPIN (-625 3550) BN 14
J 0
(-637 3558);
DISPLAY 0.680851 (-637 3558);
PAINT GREEN (-637 3558);
FORCEPROP 2 LAST CDS_LIB standard
J 0
(-575 3550);
PAINT MONO (-575 3550);
DISPLAY INVISIBLE (-575 3550);
FORCEPROP 1 LAST BODY_TYPE PLUMBING
J 0
(-575 3600);
DISPLAY 0.872340 (-575 3600);
PAINT GREEN (-575 3600);
DISPLAY INVISIBLE (-575 3600);
FORCEPROP 1 LAST HDL_TAP TRUE
J 0
(-250 3425);
DISPLAY 0.872340 (-250 3425);
DISPLAY INVISIBLE (-250 3425);
FORCEPROP 1 LAST PATH I100
J 0
(-577 3550);
DISPLAY 0.872340 (-577 3550);
PAINT GREEN (-577 3550);
DISPLAY INVISIBLE (-577 3550);
FORCEADD TAP..1
(-575 3350);
FORCEPROP 3 LASTPIN (-625 3350) SIG_NAME M_B_CPU1_SA_DQ<10>
J 0
(-615 3360);
DISPLAY 0.659574 (-615 3360);
PAINT MONO (-615 3360);
DISPLAY INVISIBLE (-615 3360);
FORCEPROP 1 LASTPIN (-625 3350) BN 10
J 0
(-637 3358);
DISPLAY 0.680851 (-637 3358);
PAINT GREEN (-637 3358);
FORCEPROP 2 LAST CDS_LIB standard
J 0
(-575 3350);
PAINT MONO (-575 3350);
DISPLAY INVISIBLE (-575 3350);
FORCEPROP 1 LAST BODY_TYPE PLUMBING
J 0
(-575 3400);
DISPLAY 0.872340 (-575 3400);
PAINT GREEN (-575 3400);
DISPLAY INVISIBLE (-575 3400);
FORCEPROP 1 LAST HDL_TAP TRUE
J 0
(-250 3225);
DISPLAY 0.872340 (-250 3225);
DISPLAY INVISIBLE (-250 3225);
FORCEPROP 1 LAST PATH I101
J 0
(-577 3350);
DISPLAY 0.872340 (-577 3350);
PAINT GREEN (-577 3350);
DISPLAY INVISIBLE (-577 3350);
FORCEADD TAP..1
(-575 3400);
FORCEPROP 3 LASTPIN (-625 3400) SIG_NAME M_B_CPU1_SA_DQ<11>
J 0
(-615 3410);
DISPLAY 0.659574 (-615 3410);
PAINT MONO (-615 3410);
DISPLAY INVISIBLE (-615 3410);
FORCEPROP 1 LASTPIN (-625 3400) BN 11
J 0
(-637 3408);
DISPLAY 0.680851 (-637 3408);
PAINT GREEN (-637 3408);
FORCEPROP 2 LAST CDS_LIB standard
J 0
(-575 3400);
PAINT MONO (-575 3400);
DISPLAY INVISIBLE (-575 3400);
FORCEPROP 1 LAST BODY_TYPE PLUMBING
J 0
(-575 3450);
DISPLAY 0.872340 (-575 3450);
PAINT GREEN (-575 3450);
DISPLAY INVISIBLE (-575 3450);
FORCEPROP 1 LAST HDL_TAP TRUE
J 0
(-250 3275);
DISPLAY 0.872340 (-250 3275);
DISPLAY INVISIBLE (-250 3275);
FORCEPROP 1 LAST PATH I102
J 0
(-577 3400);
DISPLAY 0.872340 (-577 3400);
PAINT GREEN (-577 3400);
DISPLAY INVISIBLE (-577 3400);
FORCEADD TAP..1
(-575 3800);
FORCEPROP 3 LASTPIN (-625 3800) SIG_NAME M_B_CPU1_SA_DQ<19>
J 0
(-615 3810);
DISPLAY 0.659574 (-615 3810);
PAINT MONO (-615 3810);
DISPLAY INVISIBLE (-615 3810);
FORCEPROP 1 LASTPIN (-625 3800) BN 19
J 0
(-637 3808);
DISPLAY 0.680851 (-637 3808);
PAINT GREEN (-637 3808);
FORCEPROP 2 LAST CDS_LIB standard
J 0
(-575 3800);
PAINT MONO (-575 3800);
DISPLAY INVISIBLE (-575 3800);
FORCEPROP 1 LAST BODY_TYPE PLUMBING
J 0
(-575 3850);
DISPLAY 0.872340 (-575 3850);
PAINT GREEN (-575 3850);
DISPLAY INVISIBLE (-575 3850);
FORCEPROP 1 LAST HDL_TAP TRUE
J 0
(-250 3675);
DISPLAY 0.872340 (-250 3675);
DISPLAY INVISIBLE (-250 3675);
FORCEPROP 1 LAST PATH I103
J 0
(-577 3800);
DISPLAY 0.872340 (-577 3800);
PAINT GREEN (-577 3800);
DISPLAY INVISIBLE (-577 3800);
FORCEADD TAP..1
(-575 3750);
FORCEPROP 3 LASTPIN (-625 3750) SIG_NAME M_B_CPU1_SA_DQ<18>
J 0
(-615 3760);
DISPLAY 0.659574 (-615 3760);
PAINT MONO (-615 3760);
DISPLAY INVISIBLE (-615 3760);
FORCEPROP 1 LASTPIN (-625 3750) BN 18
J 0
(-637 3758);
DISPLAY 0.680851 (-637 3758);
PAINT GREEN (-637 3758);
FORCEPROP 2 LAST CDS_LIB standard
J 0
(-575 3750);
PAINT MONO (-575 3750);
DISPLAY INVISIBLE (-575 3750);
FORCEPROP 1 LAST BODY_TYPE PLUMBING
J 0
(-575 3800);
DISPLAY 0.872340 (-575 3800);
PAINT GREEN (-575 3800);
DISPLAY INVISIBLE (-575 3800);
FORCEPROP 1 LAST HDL_TAP TRUE
J 0
(-250 3625);
DISPLAY 0.872340 (-250 3625);
DISPLAY INVISIBLE (-250 3625);
FORCEPROP 1 LAST PATH I104
J 0
(-577 3750);
DISPLAY 0.872340 (-577 3750);
PAINT GREEN (-577 3750);
DISPLAY INVISIBLE (-577 3750);
FORCEADD TAP..1
(-575 3600);
FORCEPROP 3 LASTPIN (-625 3600) SIG_NAME M_B_CPU1_SA_DQ<15>
J 0
(-615 3610);
DISPLAY 0.659574 (-615 3610);
PAINT MONO (-615 3610);
DISPLAY INVISIBLE (-615 3610);
FORCEPROP 1 LASTPIN (-625 3600) BN 15
J 0
(-637 3608);
DISPLAY 0.680851 (-637 3608);
PAINT GREEN (-637 3608);
FORCEPROP 2 LAST CDS_LIB standard
J 0
(-575 3600);
PAINT MONO (-575 3600);
DISPLAY INVISIBLE (-575 3600);
FORCEPROP 1 LAST BODY_TYPE PLUMBING
J 0
(-575 3650);
DISPLAY 0.872340 (-575 3650);
PAINT GREEN (-575 3650);
DISPLAY INVISIBLE (-575 3650);
FORCEPROP 1 LAST HDL_TAP TRUE
J 0
(-250 3475);
DISPLAY 0.872340 (-250 3475);
DISPLAY INVISIBLE (-250 3475);
FORCEPROP 1 LAST PATH I105
J 0
(-577 3600);
DISPLAY 0.872340 (-577 3600);
PAINT GREEN (-577 3600);
DISPLAY INVISIBLE (-577 3600);
FORCEADD TAP..1
(-575 3650);
FORCEPROP 3 LASTPIN (-625 3650) SIG_NAME M_B_CPU1_SA_DQ<16>
J 0
(-615 3660);
DISPLAY 0.659574 (-615 3660);
PAINT MONO (-615 3660);
DISPLAY INVISIBLE (-615 3660);
FORCEPROP 1 LASTPIN (-625 3650) BN 16
J 0
(-637 3658);
DISPLAY 0.680851 (-637 3658);
PAINT GREEN (-637 3658);
FORCEPROP 2 LAST CDS_LIB standard
J 0
(-575 3650);
PAINT MONO (-575 3650);
DISPLAY INVISIBLE (-575 3650);
FORCEPROP 1 LAST BODY_TYPE PLUMBING
J 0
(-575 3700);
DISPLAY 0.872340 (-575 3700);
PAINT GREEN (-575 3700);
DISPLAY INVISIBLE (-575 3700);
FORCEPROP 1 LAST HDL_TAP TRUE
J 0
(-250 3525);
DISPLAY 0.872340 (-250 3525);
DISPLAY INVISIBLE (-250 3525);
FORCEPROP 1 LAST PATH I106
J 0
(-577 3650);
DISPLAY 0.872340 (-577 3650);
PAINT GREEN (-577 3650);
DISPLAY INVISIBLE (-577 3650);
FORCEADD TAP..1
(-575 3700);
FORCEPROP 3 LASTPIN (-625 3700) SIG_NAME M_B_CPU1_SA_DQ<17>
J 0
(-615 3710);
DISPLAY 0.659574 (-615 3710);
PAINT MONO (-615 3710);
DISPLAY INVISIBLE (-615 3710);
FORCEPROP 1 LASTPIN (-625 3700) BN 17
J 0
(-637 3708);
DISPLAY 0.680851 (-637 3708);
PAINT GREEN (-637 3708);
FORCEPROP 2 LAST CDS_LIB standard
J 0
(-575 3700);
PAINT MONO (-575 3700);
DISPLAY INVISIBLE (-575 3700);
FORCEPROP 1 LAST BODY_TYPE PLUMBING
J 0
(-575 3750);
DISPLAY 0.872340 (-575 3750);
PAINT GREEN (-575 3750);
DISPLAY INVISIBLE (-575 3750);
FORCEPROP 1 LAST HDL_TAP TRUE
J 0
(-250 3575);
DISPLAY 0.872340 (-250 3575);
DISPLAY INVISIBLE (-250 3575);
FORCEPROP 1 LAST PATH I107
J 0
(-577 3700);
DISPLAY 0.872340 (-577 3700);
PAINT GREEN (-577 3700);
DISPLAY INVISIBLE (-577 3700);
FORCEADD TAP..1
(-575 4000);
FORCEPROP 3 LASTPIN (-625 4000) SIG_NAME M_B_CPU1_SA_DQ<23>
J 0
(-615 4010);
DISPLAY 0.659574 (-615 4010);
PAINT MONO (-615 4010);
DISPLAY INVISIBLE (-615 4010);
FORCEPROP 1 LASTPIN (-625 4000) BN 23
J 0
(-637 4008);
DISPLAY 0.680851 (-637 4008);
PAINT GREEN (-637 4008);
FORCEPROP 2 LAST CDS_LIB standard
J 0
(-575 4000);
DISPLAY INVISIBLE (-575 4000);
FORCEPROP 1 LAST BODY_TYPE PLUMBING
J 0
(-575 4050);
DISPLAY 0.872340 (-575 4050);
PAINT GREEN (-575 4050);
DISPLAY INVISIBLE (-575 4050);
FORCEPROP 1 LAST HDL_TAP TRUE
J 0
(-250 3875);
DISPLAY 0.872340 (-250 3875);
DISPLAY INVISIBLE (-250 3875);
FORCEPROP 1 LAST PATH I108
J 0
(-577 4000);
DISPLAY 0.872340 (-577 4000);
PAINT GREEN (-577 4000);
DISPLAY INVISIBLE (-577 4000);
FORCEADD TAP..1
(-575 4050);
FORCEPROP 3 LASTPIN (-625 4050) SIG_NAME M_B_CPU1_SA_DQ<24>
J 0
(-615 4060);
DISPLAY 0.659574 (-615 4060);
PAINT MONO (-615 4060);
DISPLAY INVISIBLE (-615 4060);
FORCEPROP 1 LASTPIN (-625 4050) BN 24
J 0
(-637 4058);
DISPLAY 0.680851 (-637 4058);
PAINT GREEN (-637 4058);
FORCEPROP 2 LAST CDS_LIB standard
J 0
(-575 4050);
DISPLAY INVISIBLE (-575 4050);
FORCEPROP 1 LAST BODY_TYPE PLUMBING
J 0
(-575 4100);
DISPLAY 0.872340 (-575 4100);
PAINT GREEN (-575 4100);
DISPLAY INVISIBLE (-575 4100);
FORCEPROP 1 LAST HDL_TAP TRUE
J 0
(-250 3925);
DISPLAY 0.872340 (-250 3925);
DISPLAY INVISIBLE (-250 3925);
FORCEPROP 1 LAST PATH I109
J 0
(-577 4050);
DISPLAY 0.872340 (-577 4050);
PAINT GREEN (-577 4050);
DISPLAY INVISIBLE (-577 4050);
FORCEADD OFFPAGE..1
(-3150 2150);
FORCEPROP 2 LAST $XR3 101 
J 0
(-3402 2114);
DISPLAY 0.638298 (-3402 2114);
PAINT MONO (-3402 2114);
FORCEPROP 2 LAST $XR2 99 
J 0
(-3582 2150);
DISPLAY 0.638298 (-3582 2150);
PAINT MONO (-3582 2150);
FORCEPROP 2 LAST $XR1 98 
J 0
(-3492 2150);
DISPLAY 0.638298 (-3492 2150);
PAINT MONO (-3492 2150);
FORCEPROP 2 LAST $XR0 130 
J 0
(-3402 2150);
DISPLAY 0.638298 (-3402 2150);
PAINT MONO (-3402 2150);
FORCEPROP 2 LAST CDS_LIB standard
J 0
(-3150 2150);
PAINT MONO (-3150 2150);
DISPLAY INVISIBLE (-3150 2150);
FORCEPROP 1 LAST OFFPAGE TRUE
J 0
(-2825 2025);
DISPLAY 0.872340 (-2825 2025);
DISPLAY INVISIBLE (-2825 2025);
FORCEPROP 1 LAST COMMENT_BODY TRUE
J 0
(-3025 2050);
DISPLAY 0.872340 (-3025 2050);
PAINT GREEN (-3025 2050);
DISPLAY INVISIBLE (-3025 2050);
FORCEPROP 2 LAST PATH I11
J 0
(-3100 2225);
DISPLAY 1.021277 (-3100 2225);
DISPLAY INVISIBLE (-3100 2225);
FORCEADD TAP..1
(-575 3950);
FORCEPROP 3 LASTPIN (-625 3950) SIG_NAME M_B_CPU1_SA_DQ<22>
J 0
(-615 3960);
DISPLAY 0.659574 (-615 3960);
PAINT MONO (-615 3960);
DISPLAY INVISIBLE (-615 3960);
FORCEPROP 1 LASTPIN (-625 3950) BN 22
J 0
(-637 3958);
DISPLAY 0.680851 (-637 3958);
PAINT GREEN (-637 3958);
FORCEPROP 2 LAST CDS_LIB standard
J 0
(-575 3950);
DISPLAY INVISIBLE (-575 3950);
FORCEPROP 1 LAST BODY_TYPE PLUMBING
J 0
(-575 4000);
DISPLAY 0.872340 (-575 4000);
PAINT GREEN (-575 4000);
DISPLAY INVISIBLE (-575 4000);
FORCEPROP 1 LAST HDL_TAP TRUE
J 0
(-250 3825);
DISPLAY 0.872340 (-250 3825);
DISPLAY INVISIBLE (-250 3825);
FORCEPROP 1 LAST PATH I110
J 0
(-577 3950);
DISPLAY 0.872340 (-577 3950);
PAINT GREEN (-577 3950);
DISPLAY INVISIBLE (-577 3950);
FORCEADD TAP..1
(-575 3900);
FORCEPROP 3 LASTPIN (-625 3900) SIG_NAME M_B_CPU1_SA_DQ<21>
J 0
(-615 3910);
DISPLAY 0.659574 (-615 3910);
PAINT MONO (-615 3910);
DISPLAY INVISIBLE (-615 3910);
FORCEPROP 1 LASTPIN (-625 3900) BN 21
J 0
(-637 3908);
DISPLAY 0.680851 (-637 3908);
PAINT GREEN (-637 3908);
FORCEPROP 2 LAST CDS_LIB standard
J 0
(-575 3900);
PAINT MONO (-575 3900);
DISPLAY INVISIBLE (-575 3900);
FORCEPROP 1 LAST BODY_TYPE PLUMBING
J 0
(-575 3950);
DISPLAY 0.872340 (-575 3950);
PAINT GREEN (-575 3950);
DISPLAY INVISIBLE (-575 3950);
FORCEPROP 1 LAST HDL_TAP TRUE
J 0
(-250 3775);
DISPLAY 0.872340 (-250 3775);
DISPLAY INVISIBLE (-250 3775);
FORCEPROP 1 LAST PATH I111
J 0
(-577 3900);
DISPLAY 0.872340 (-577 3900);
PAINT GREEN (-577 3900);
DISPLAY INVISIBLE (-577 3900);
FORCEADD TAP..1
(-575 3850);
FORCEPROP 3 LASTPIN (-625 3850) SIG_NAME M_B_CPU1_SA_DQ<20>
J 0
(-615 3860);
DISPLAY 0.659574 (-615 3860);
PAINT MONO (-615 3860);
DISPLAY INVISIBLE (-615 3860);
FORCEPROP 1 LASTPIN (-625 3850) BN 20
J 0
(-637 3858);
DISPLAY 0.680851 (-637 3858);
PAINT GREEN (-637 3858);
FORCEPROP 2 LAST CDS_LIB standard
J 0
(-575 3850);
PAINT MONO (-575 3850);
DISPLAY INVISIBLE (-575 3850);
FORCEPROP 1 LAST BODY_TYPE PLUMBING
J 0
(-575 3900);
DISPLAY 0.872340 (-575 3900);
PAINT GREEN (-575 3900);
DISPLAY INVISIBLE (-575 3900);
FORCEPROP 1 LAST HDL_TAP TRUE
J 0
(-250 3725);
DISPLAY 0.872340 (-250 3725);
DISPLAY INVISIBLE (-250 3725);
FORCEPROP 1 LAST PATH I112
J 0
(-577 3850);
DISPLAY 0.872340 (-577 3850);
PAINT GREEN (-577 3850);
DISPLAY INVISIBLE (-577 3850);
FORCEADD TAP..1
(-575 4200);
FORCEPROP 3 LASTPIN (-625 4200) SIG_NAME M_B_CPU1_SA_DQ<27>
J 0
(-615 4210);
DISPLAY 0.659574 (-615 4210);
PAINT MONO (-615 4210);
DISPLAY INVISIBLE (-615 4210);
FORCEPROP 1 LASTPIN (-625 4200) BN 27
J 0
(-637 4208);
DISPLAY 0.680851 (-637 4208);
PAINT GREEN (-637 4208);
FORCEPROP 2 LAST CDS_LIB standard
J 0
(-575 4200);
DISPLAY INVISIBLE (-575 4200);
FORCEPROP 1 LAST BODY_TYPE PLUMBING
J 0
(-575 4250);
DISPLAY 0.872340 (-575 4250);
PAINT GREEN (-575 4250);
DISPLAY INVISIBLE (-575 4250);
FORCEPROP 1 LAST HDL_TAP TRUE
J 0
(-250 4075);
DISPLAY 0.872340 (-250 4075);
DISPLAY INVISIBLE (-250 4075);
FORCEPROP 1 LAST PATH I113
J 0
(-577 4200);
DISPLAY 0.872340 (-577 4200);
PAINT GREEN (-577 4200);
DISPLAY INVISIBLE (-577 4200);
FORCEADD TAP..1
(-575 4250);
FORCEPROP 3 LASTPIN (-625 4250) SIG_NAME M_B_CPU1_SA_DQ<28>
J 0
(-615 4260);
DISPLAY 0.659574 (-615 4260);
PAINT MONO (-615 4260);
DISPLAY INVISIBLE (-615 4260);
FORCEPROP 1 LASTPIN (-625 4250) BN 28
J 0
(-637 4258);
DISPLAY 0.680851 (-637 4258);
PAINT GREEN (-637 4258);
FORCEPROP 2 LAST CDS_LIB standard
J 0
(-575 4250);
DISPLAY INVISIBLE (-575 4250);
FORCEPROP 1 LAST BODY_TYPE PLUMBING
J 0
(-575 4300);
DISPLAY 0.872340 (-575 4300);
PAINT GREEN (-575 4300);
DISPLAY INVISIBLE (-575 4300);
FORCEPROP 1 LAST HDL_TAP TRUE
J 0
(-250 4125);
DISPLAY 0.872340 (-250 4125);
DISPLAY INVISIBLE (-250 4125);
FORCEPROP 1 LAST PATH I114
J 0
(-577 4250);
DISPLAY 0.872340 (-577 4250);
PAINT GREEN (-577 4250);
DISPLAY INVISIBLE (-577 4250);
FORCEADD TAP..1
(-575 4300);
FORCEPROP 3 LASTPIN (-625 4300) SIG_NAME M_B_CPU1_SA_DQ<29>
J 0
(-615 4310);
DISPLAY 0.659574 (-615 4310);
PAINT MONO (-615 4310);
DISPLAY INVISIBLE (-615 4310);
FORCEPROP 1 LASTPIN (-625 4300) BN 29
J 0
(-637 4308);
DISPLAY 0.680851 (-637 4308);
PAINT GREEN (-637 4308);
FORCEPROP 2 LAST CDS_LIB standard
J 0
(-575 4300);
DISPLAY INVISIBLE (-575 4300);
FORCEPROP 1 LAST BODY_TYPE PLUMBING
J 0
(-575 4350);
DISPLAY 0.872340 (-575 4350);
PAINT GREEN (-575 4350);
DISPLAY INVISIBLE (-575 4350);
FORCEPROP 1 LAST HDL_TAP TRUE
J 0
(-250 4175);
DISPLAY 0.872340 (-250 4175);
DISPLAY INVISIBLE (-250 4175);
FORCEPROP 1 LAST PATH I115
J 0
(-577 4300);
DISPLAY 0.872340 (-577 4300);
PAINT GREEN (-577 4300);
DISPLAY INVISIBLE (-577 4300);
FORCEADD TAP..1
(-575 4150);
FORCEPROP 3 LASTPIN (-625 4150) SIG_NAME M_B_CPU1_SA_DQ<26>
J 0
(-615 4160);
DISPLAY 0.659574 (-615 4160);
PAINT MONO (-615 4160);
DISPLAY INVISIBLE (-615 4160);
FORCEPROP 1 LASTPIN (-625 4150) BN 26
J 0
(-637 4158);
DISPLAY 0.680851 (-637 4158);
PAINT GREEN (-637 4158);
FORCEPROP 2 LAST CDS_LIB standard
J 0
(-575 4150);
DISPLAY INVISIBLE (-575 4150);
FORCEPROP 1 LAST BODY_TYPE PLUMBING
J 0
(-575 4200);
DISPLAY 0.872340 (-575 4200);
PAINT GREEN (-575 4200);
DISPLAY INVISIBLE (-575 4200);
FORCEPROP 1 LAST HDL_TAP TRUE
J 0
(-250 4025);
DISPLAY 0.872340 (-250 4025);
DISPLAY INVISIBLE (-250 4025);
FORCEPROP 1 LAST PATH I116
J 0
(-577 4150);
DISPLAY 0.872340 (-577 4150);
PAINT GREEN (-577 4150);
DISPLAY INVISIBLE (-577 4150);
FORCEADD TAP..1
(-575 4100);
FORCEPROP 3 LASTPIN (-625 4100) SIG_NAME M_B_CPU1_SA_DQ<25>
J 0
(-615 4110);
DISPLAY 0.659574 (-615 4110);
PAINT MONO (-615 4110);
DISPLAY INVISIBLE (-615 4110);
FORCEPROP 1 LASTPIN (-625 4100) BN 25
J 0
(-637 4108);
DISPLAY 0.680851 (-637 4108);
PAINT GREEN (-637 4108);
FORCEPROP 2 LAST CDS_LIB standard
J 0
(-575 4100);
DISPLAY INVISIBLE (-575 4100);
FORCEPROP 1 LAST BODY_TYPE PLUMBING
J 0
(-575 4150);
DISPLAY 0.872340 (-575 4150);
PAINT GREEN (-575 4150);
DISPLAY INVISIBLE (-575 4150);
FORCEPROP 1 LAST HDL_TAP TRUE
J 0
(-250 3975);
DISPLAY 0.872340 (-250 3975);
DISPLAY INVISIBLE (-250 3975);
FORCEPROP 1 LAST PATH I117
J 0
(-577 4100);
DISPLAY 0.872340 (-577 4100);
PAINT GREEN (-577 4100);
DISPLAY INVISIBLE (-577 4100);
FORCEADD TAP..1
(-575 4400);
FORCEPROP 3 LASTPIN (-625 4400) SIG_NAME M_B_CPU1_SA_DQ<31>
J 0
(-615 4410);
DISPLAY 0.659574 (-615 4410);
PAINT MONO (-615 4410);
DISPLAY INVISIBLE (-615 4410);
FORCEPROP 1 LASTPIN (-625 4400) BN 31
J 0
(-637 4408);
DISPLAY 0.680851 (-637 4408);
PAINT GREEN (-637 4408);
FORCEPROP 2 LAST CDS_LIB standard
J 0
(-575 4400);
DISPLAY INVISIBLE (-575 4400);
FORCEPROP 1 LAST BODY_TYPE PLUMBING
J 0
(-575 4450);
DISPLAY 0.872340 (-575 4450);
PAINT GREEN (-575 4450);
DISPLAY INVISIBLE (-575 4450);
FORCEPROP 1 LAST HDL_TAP TRUE
J 0
(-250 4275);
DISPLAY 0.872340 (-250 4275);
DISPLAY INVISIBLE (-250 4275);
FORCEPROP 1 LAST PATH I118
J 0
(-577 4400);
DISPLAY 0.872340 (-577 4400);
PAINT GREEN (-577 4400);
DISPLAY INVISIBLE (-577 4400);
FORCEADD TAP..1
(-575 4350);
FORCEPROP 3 LASTPIN (-625 4350) SIG_NAME M_B_CPU1_SA_DQ<30>
J 0
(-615 4360);
DISPLAY 0.659574 (-615 4360);
PAINT MONO (-615 4360);
DISPLAY INVISIBLE (-615 4360);
FORCEPROP 1 LASTPIN (-625 4350) BN 30
J 0
(-637 4358);
DISPLAY 0.680851 (-637 4358);
PAINT GREEN (-637 4358);
FORCEPROP 2 LAST CDS_LIB standard
J 0
(-575 4350);
DISPLAY INVISIBLE (-575 4350);
FORCEPROP 1 LAST BODY_TYPE PLUMBING
J 0
(-575 4400);
DISPLAY 0.872340 (-575 4400);
PAINT GREEN (-575 4400);
DISPLAY INVISIBLE (-575 4400);
FORCEPROP 1 LAST HDL_TAP TRUE
J 0
(-250 4225);
DISPLAY 0.872340 (-250 4225);
DISPLAY INVISIBLE (-250 4225);
FORCEPROP 1 LAST PATH I119
J 0
(-577 4350);
DISPLAY 0.872340 (-577 4350);
PAINT GREEN (-577 4350);
DISPLAY INVISIBLE (-577 4350);
FORCEADD OFFPAGE..3
R 2
(-3150 2575);
FORCEPROP 2 LAST $XR1 101 
J 0
(-3519 2575);
DISPLAY 0.638298 (-3519 2575);
PAINT MONO (-3519 2575);
FORCEPROP 2 LAST $XR0 52 
J 0
(-3399 2575);
DISPLAY 0.638298 (-3399 2575);
PAINT MONO (-3399 2575);
FORCEPROP 2 LAST CDS_LIB standard
J 0
(-3150 2575);
PAINT MONO (-3150 2575);
DISPLAY INVISIBLE (-3150 2575);
FORCEPROP 1 LAST OFFPAGE TRUE
J 2
(-3475 2450);
DISPLAY 0.872340 (-3475 2450);
DISPLAY INVISIBLE (-3475 2450);
FORCEPROP 1 LAST COMMENT_BODY TRUE
J 2
(-3100 2475);
DISPLAY 0.872340 (-3100 2475);
PAINT GREEN (-3100 2475);
DISPLAY INVISIBLE (-3100 2475);
FORCEPROP 2 LAST PATH I12
J 0
(-3100 2650);
DISPLAY 1.021277 (-3100 2650);
DISPLAY INVISIBLE (-3100 2650);
FORCEADD UNIVERSAL_GND..1
(1150 150);
FORCEPROP 3 LASTPIN (1150 200) SIG_NAME GND\g
J 0
(1160 210);
DISPLAY 0.659574 (1160 210);
PAINT MONO (1160 210);
DISPLAY INVISIBLE (1160 210);
FORCEPROP 1 LAST PATH I120
J 0
(1225 150);
DISPLAY 0.872340 (1225 150);
PAINT AQUA (1225 150);
DISPLAY INVISIBLE (1225 150);
FORCEPROP 1 LAST HDL_POWER GND
J 1
(1175 75);
DISPLAY 0.872340 (1175 75);
PAINT GREEN (1175 75);
DISPLAY INVISIBLE (1175 75);
FORCEPROP 2 LAST CDS_LIB logical_power
J 0
(1150 150);
PAINT MONO (1150 150);
DISPLAY INVISIBLE (1150 150);
FORCEADD Q_CAP..1
(1150 525);
FORCEPROP 1 LAST PART_NUMBER CH5221MEB00
J 0
(1200 375);
DISPLAY 0.978723 (1200 375);
DISPLAY INVISIBLE (1200 375);
FORCEPROP 1 LAST MATERIAL X6S
J 0
(1200 425);
DISPLAY 0.978723 (1200 425);
FORCEPROP 1 LAST TOLERANCE 20%
J 0
(1200 475);
DISPLAY 0.978723 (1200 475);
FORCEPROP 1 LAST VALUE 2.2UF
J 0
(1200 575);
DISPLAY 0.978723 (1200 575);
FORCEPROP 1 LAST VOLTAGE 6.3V
J 0
(1200 525);
DISPLAY 0.978723 (1200 525);
FORCEPROP 1 LAST PACK_TYPE C0402
J 0
(1200 325);
DISPLAY 0.978723 (1200 325);
FORCEPROP 1 LAST $LOCATION C56
J 0
(1200 625);
DISPLAY 0.978723 (1200 625);
FORCEPROP 1 LASTPIN (1150 625) $PN 1
J 0
(1160 605);
DISPLAY 0.787234 (1160 605);
FORCEPROP 1 LASTPIN (1150 425) $PN 2
J 0
(1160 405);
DISPLAY 0.787234 (1160 405);
FORCEPROP 2 LAST CDS_LIB pure_quanta
J 0
(1150 525);
PAINT MONO (1150 525);
DISPLAY INVISIBLE (1150 525);
FORCEPROP 1 LAST PATH I121
J 0
(1200 675);
DISPLAY 0.978723 (1200 675);
PAINT WHITE (1200 675);
DISPLAY INVISIBLE (1200 675);
FORCEPROP 2 LAST CDS_LOCATION C56
J 0
(1200 725);
DISPLAY 1.021277 (1200 725);
DISPLAY INVISIBLE (1200 725);
FORCEPROP 2 LAST $SEC 1
J 0
(1200 725);
DISPLAY 0.680851 (1200 725);
PAINT MONO (1200 725);
DISPLAY INVISIBLE (1200 725);
FORCEPROP 2 LAST CDS_SEC 1
J 0
(1200 725);
DISPLAY 1.021277 (1200 725);
DISPLAY INVISIBLE (1200 725);
FORCEADD Q_CAP..1
(2150 525);
FORCEPROP 1 LAST PART_NUMBER CH6103KEA00
J 0
(2200 375);
DISPLAY 0.978723 (2200 375);
DISPLAY INVISIBLE (2200 375);
FORCEPROP 1 LAST PACK_TYPE C0805
J 0
(2200 325);
DISPLAY 0.978723 (2200 325);
FORCEPROP 1 LAST TOLERANCE 10%
J 0
(2200 475);
DISPLAY 0.978723 (2200 475);
FORCEPROP 1 LAST VOLTAGE 16V
J 0
(2200 525);
DISPLAY 0.978723 (2200 525);
FORCEPROP 1 LAST VALUE 10UF
J 0
(2200 575);
DISPLAY 0.978723 (2200 575);
FORCEPROP 1 LAST MATERIAL X6S
J 0
(2200 425);
DISPLAY 0.978723 (2200 425);
FORCEPROP 1 LAST $LOCATION C57
J 0
(2200 625);
DISPLAY 0.978723 (2200 625);
FORCEPROP 1 LASTPIN (2150 625) $PN 1
J 0
(2160 605);
DISPLAY 0.787234 (2160 605);
FORCEPROP 1 LASTPIN (2150 425) $PN 2
J 0
(2160 405);
DISPLAY 0.787234 (2160 405);
FORCEPROP 2 LAST CDS_LIB pure_quanta
J 0
(2150 525);
PAINT MONO (2150 525);
DISPLAY INVISIBLE (2150 525);
FORCEPROP 1 LAST PATH I122
J 0
(2200 675);
DISPLAY 0.978723 (2200 675);
PAINT WHITE (2200 675);
DISPLAY INVISIBLE (2200 675);
FORCEPROP 2 LAST CDS_LOCATION C57
J 0
(2200 725);
DISPLAY 1.021277 (2200 725);
DISPLAY INVISIBLE (2200 725);
FORCEPROP 2 LAST $SEC 1
J 0
(2200 725);
DISPLAY 0.680851 (2200 725);
PAINT MONO (2200 725);
DISPLAY INVISIBLE (2200 725);
FORCEPROP 2 LAST CDS_SEC 1
J 0
(2200 725);
DISPLAY 1.021277 (2200 725);
DISPLAY INVISIBLE (2200 725);
FORCEADD UNIVERSAL_GND..1
(2775 150);
FORCEPROP 3 LASTPIN (2775 200) SIG_NAME GND\g
J 0
(2785 210);
DISPLAY 0.659574 (2785 210);
PAINT MONO (2785 210);
DISPLAY INVISIBLE (2785 210);
FORCEPROP 1 LAST PATH I123
J 0
(2850 150);
DISPLAY 0.872340 (2850 150);
PAINT AQUA (2850 150);
DISPLAY INVISIBLE (2850 150);
FORCEPROP 1 LAST HDL_POWER GND
J 1
(2800 75);
DISPLAY 0.872340 (2800 75);
PAINT GREEN (2800 75);
DISPLAY INVISIBLE (2800 75);
FORCEPROP 2 LAST CDS_LIB logical_power
J 0
(2775 150);
PAINT MONO (2775 150);
DISPLAY INVISIBLE (2775 150);
FORCEADD Q_CAP..1
(2775 525);
FORCEPROP 1 LAST PART_NUMBER CH6103KEA00
J 0
(2825 375);
DISPLAY 0.978723 (2825 375);
DISPLAY INVISIBLE (2825 375);
FORCEPROP 1 LAST PACK_TYPE C0805
J 0
(2825 325);
DISPLAY 0.978723 (2825 325);
FORCEPROP 1 LAST TOLERANCE 10%
J 0
(2825 475);
DISPLAY 0.978723 (2825 475);
FORCEPROP 1 LAST VOLTAGE 16V
J 0
(2825 525);
DISPLAY 0.978723 (2825 525);
FORCEPROP 1 LAST VALUE 10UF
J 0
(2825 575);
DISPLAY 0.978723 (2825 575);
FORCEPROP 1 LAST MATERIAL X6S
J 0
(2825 425);
DISPLAY 0.978723 (2825 425);
FORCEPROP 1 LAST $LOCATION C58
J 0
(2825 625);
DISPLAY 0.978723 (2825 625);
FORCEPROP 1 LASTPIN (2775 625) $PN 1
J 0
(2785 605);
DISPLAY 0.787234 (2785 605);
FORCEPROP 1 LASTPIN (2775 425) $PN 2
J 0
(2785 405);
DISPLAY 0.787234 (2785 405);
FORCEPROP 2 LAST CDS_LIB pure_quanta
J 0
(2775 525);
PAINT MONO (2775 525);
DISPLAY INVISIBLE (2775 525);
FORCEPROP 1 LAST PATH I124
J 0
(2825 675);
DISPLAY 0.978723 (2825 675);
PAINT WHITE (2825 675);
DISPLAY INVISIBLE (2825 675);
FORCEPROP 2 LAST CDS_LOCATION C58
J 0
(2825 725);
DISPLAY 1.021277 (2825 725);
DISPLAY INVISIBLE (2825 725);
FORCEPROP 2 LAST $SEC 1
J 0
(2825 725);
DISPLAY 0.680851 (2825 725);
PAINT MONO (2825 725);
DISPLAY INVISIBLE (2825 725);
FORCEPROP 2 LAST CDS_SEC 1
J 0
(2825 725);
DISPLAY 1.021277 (2825 725);
DISPLAY INVISIBLE (2825 725);
FORCEADD VCC_CORE..1
(1150 850);
FORCEPROP 3 LASTPIN (1150 800) SIG_NAME P3V3_AUX\g
J 0
(1160 810);
DISPLAY 0.659574 (1160 810);
PAINT MONO (1160 810);
DISPLAY INVISIBLE (1160 810);
FORCEPROP 1 LAST HDL_POWER P3V3_AUX
J 1
(1150 900);
DISPLAY 1.148936 (1150 900);
PAINT GREEN (1150 900);
FORCEPROP 2 LAST CDS_LIB logical_power
J 0
(1150 850);
PAINT MONO (1150 850);
DISPLAY INVISIBLE (1150 850);
FORCEPROP 1 LAST PATH I125
J 0
(1200 875);
DISPLAY 0.872340 (1200 875);
PAINT AQUA (1200 875);
DISPLAY INVISIBLE (1200 875);
FORCEADD OFFPAGE..3
(250 2775);
FORCEPROP 2 LAST $XR1 101 
J 0
(554 2775);
DISPLAY 0.638298 (554 2775);
PAINT MONO (554 2775);
FORCEPROP 2 LAST $XR0 52 
J 0
(464 2775);
DISPLAY 0.638298 (464 2775);
PAINT MONO (464 2775);
FORCEPROP 2 LAST CDS_LIB standard
J 2
(250 2775);
DISPLAY INVISIBLE (250 2775);
FORCEPROP 1 LAST OFFPAGE TRUE
J 0
(575 2650);
DISPLAY 0.872340 (575 2650);
DISPLAY INVISIBLE (575 2650);
FORCEPROP 1 LAST COMMENT_BODY TRUE
J 0
(200 2675);
DISPLAY 0.872340 (200 2675);
PAINT GREEN (200 2675);
DISPLAY INVISIBLE (200 2675);
FORCEPROP 2 LAST PATH I127
J 0
(450 2850);
DISPLAY 1.021277 (450 2850);
DISPLAY INVISIBLE (450 2850);
FORCEADD OFFPAGE..3
(250 4425);
FORCEPROP 2 LAST $XR1 101 
J 0
(554 4425);
DISPLAY 0.638298 (554 4425);
PAINT MONO (554 4425);
FORCEPROP 2 LAST $XR0 52 
J 0
(464 4425);
DISPLAY 0.638298 (464 4425);
PAINT MONO (464 4425);
FORCEPROP 2 LAST CDS_LIB standard
J 2
(250 4425);
DISPLAY INVISIBLE (250 4425);
FORCEPROP 1 LAST OFFPAGE TRUE
J 0
(575 4300);
DISPLAY 0.872340 (575 4300);
DISPLAY INVISIBLE (575 4300);
FORCEPROP 1 LAST COMMENT_BODY TRUE
J 0
(200 4325);
DISPLAY 0.872340 (200 4325);
PAINT GREEN (200 4325);
DISPLAY INVISIBLE (200 4325);
FORCEPROP 2 LAST PATH I128
J 0
(450 4500);
DISPLAY 1.021277 (450 4500);
DISPLAY INVISIBLE (450 4500);
FORCEADD VCC_CORE..1
(2150 850);
FORCEPROP 3 LASTPIN (2150 800) SIG_NAME P12V_S3_AUX_CPU1_NVDIMM\g
J 0
(2160 810);
DISPLAY 0.659574 (2160 810);
PAINT MONO (2160 810);
DISPLAY INVISIBLE (2160 810);
FORCEPROP 1 LAST HDL_POWER P12V_S3_AUX_CPU1_NVDIMM
J 1
(2150 900);
DISPLAY 1.148936 (2150 900);
PAINT GREEN (2150 900);
FORCEPROP 2 LAST CDS_LIB logical_power
J 0
(2150 850);
PAINT MONO (2150 850);
DISPLAY INVISIBLE (2150 850);
FORCEPROP 1 LAST PATH I129
J 0
(2200 875);
DISPLAY 0.872340 (2200 875);
PAINT AQUA (2200 875);
DISPLAY INVISIBLE (2200 875);
FORCEADD VCC_CORE..1
(-3050 2275);
FORCEPROP 3 LASTPIN (-3050 2225) SIG_NAME P3V3_AUX\g
J 0
(-3040 2235);
DISPLAY 0.659574 (-3040 2235);
PAINT MONO (-3040 2235);
DISPLAY INVISIBLE (-3040 2235);
FORCEPROP 1 LAST HDL_POWER P3V3_AUX
J 1
(-3050 2325);
DISPLAY 1.148936 (-3050 2325);
PAINT GREEN (-3050 2325);
FORCEPROP 2 LAST CDS_LIB logical_power
J 0
(-3050 2275);
PAINT MONO (-3050 2275);
DISPLAY INVISIBLE (-3050 2275);
FORCEPROP 1 LAST PATH I13
J 0
(-3000 2300);
DISPLAY 0.872340 (-3000 2300);
PAINT AQUA (-3000 2300);
DISPLAY INVISIBLE (-3000 2300);
FORCEADD TAP..1
(2175 2450);
FORCEPROP 3 LASTPIN (2125 2450) SIG_NAME M_B_CPU1_SB_DQS_DP<0>
J 0
(2135 2460);
DISPLAY 0.659574 (2135 2460);
PAINT MONO (2135 2460);
DISPLAY INVISIBLE (2135 2460);
FORCEPROP 1 LASTPIN (2125 2450) BN 0
J 0
(2113 2458);
DISPLAY 0.680851 (2113 2458);
PAINT GREEN (2113 2458);
FORCEPROP 2 LAST CDS_LIB standard
J 0
(2175 2450);
PAINT MONO (2175 2450);
DISPLAY INVISIBLE (2175 2450);
FORCEPROP 1 LAST BODY_TYPE PLUMBING
J 0
(2175 2500);
DISPLAY 0.872340 (2175 2500);
PAINT GREEN (2175 2500);
DISPLAY INVISIBLE (2175 2500);
FORCEPROP 1 LAST HDL_TAP TRUE
J 0
(2500 2325);
DISPLAY 0.872340 (2500 2325);
DISPLAY INVISIBLE (2500 2325);
FORCEPROP 1 LAST PATH I130
J 0
(2173 2450);
DISPLAY 0.872340 (2173 2450);
PAINT GREEN (2173 2450);
DISPLAY INVISIBLE (2173 2450);
FORCEADD TAP..1
(2350 2400);
FORCEPROP 3 LASTPIN (2300 2400) SIG_NAME M_B_CPU1_SB_DQS_DN<0>
J 0
(2310 2410);
DISPLAY 0.659574 (2310 2410);
PAINT MONO (2310 2410);
DISPLAY INVISIBLE (2310 2410);
FORCEPROP 1 LASTPIN (2300 2400) BN 0
J 0
(2288 2408);
DISPLAY 0.680851 (2288 2408);
PAINT GREEN (2288 2408);
FORCEPROP 2 LAST CDS_LIB standard
J 0
(2350 2400);
PAINT MONO (2350 2400);
DISPLAY INVISIBLE (2350 2400);
FORCEPROP 1 LAST BODY_TYPE PLUMBING
J 0
(2350 2450);
DISPLAY 0.872340 (2350 2450);
PAINT GREEN (2350 2450);
DISPLAY INVISIBLE (2350 2450);
FORCEPROP 1 LAST HDL_TAP TRUE
J 0
(2675 2275);
DISPLAY 0.872340 (2675 2275);
DISPLAY INVISIBLE (2675 2275);
FORCEPROP 1 LAST PATH I131
J 0
(2348 2400);
DISPLAY 0.872340 (2348 2400);
PAINT GREEN (2348 2400);
DISPLAY INVISIBLE (2348 2400);
FORCEADD TAP..1
(2350 2500);
FORCEPROP 3 LASTPIN (2300 2500) SIG_NAME M_B_CPU1_SB_DQS_DN<1>
J 0
(2310 2510);
DISPLAY 0.659574 (2310 2510);
PAINT MONO (2310 2510);
DISPLAY INVISIBLE (2310 2510);
FORCEPROP 1 LASTPIN (2300 2500) BN 1
J 0
(2288 2508);
DISPLAY 0.680851 (2288 2508);
PAINT GREEN (2288 2508);
FORCEPROP 2 LAST CDS_LIB standard
J 0
(2350 2500);
DISPLAY INVISIBLE (2350 2500);
FORCEPROP 1 LAST BODY_TYPE PLUMBING
J 0
(2350 2550);
DISPLAY 0.872340 (2350 2550);
PAINT GREEN (2350 2550);
DISPLAY INVISIBLE (2350 2550);
FORCEPROP 1 LAST HDL_TAP TRUE
J 0
(2675 2375);
DISPLAY 0.872340 (2675 2375);
DISPLAY INVISIBLE (2675 2375);
FORCEPROP 1 LAST PATH I132
J 0
(2348 2500);
DISPLAY 0.872340 (2348 2500);
PAINT GREEN (2348 2500);
DISPLAY INVISIBLE (2348 2500);
FORCEADD TAP..1
(2175 2650);
FORCEPROP 3 LASTPIN (2125 2650) SIG_NAME M_B_CPU1_SB_DQS_DP<2>
J 0
(2135 2660);
DISPLAY 0.659574 (2135 2660);
PAINT MONO (2135 2660);
DISPLAY INVISIBLE (2135 2660);
FORCEPROP 1 LASTPIN (2125 2650) BN 2
J 0
(2113 2658);
DISPLAY 0.680851 (2113 2658);
PAINT GREEN (2113 2658);
FORCEPROP 2 LAST CDS_LIB standard
J 0
(2175 2650);
DISPLAY INVISIBLE (2175 2650);
FORCEPROP 1 LAST BODY_TYPE PLUMBING
J 0
(2175 2700);
DISPLAY 0.872340 (2175 2700);
PAINT GREEN (2175 2700);
DISPLAY INVISIBLE (2175 2700);
FORCEPROP 1 LAST HDL_TAP TRUE
J 0
(2500 2525);
DISPLAY 0.872340 (2500 2525);
DISPLAY INVISIBLE (2500 2525);
FORCEPROP 1 LAST PATH I133
J 0
(2173 2650);
DISPLAY 0.872340 (2173 2650);
PAINT GREEN (2173 2650);
DISPLAY INVISIBLE (2173 2650);
FORCEADD TAP..1
(2175 2550);
FORCEPROP 3 LASTPIN (2125 2550) SIG_NAME M_B_CPU1_SB_DQS_DP<1>
J 0
(2135 2560);
DISPLAY 0.659574 (2135 2560);
PAINT MONO (2135 2560);
DISPLAY INVISIBLE (2135 2560);
FORCEPROP 1 LASTPIN (2125 2550) BN 1
J 0
(2113 2558);
DISPLAY 0.680851 (2113 2558);
PAINT GREEN (2113 2558);
FORCEPROP 2 LAST CDS_LIB standard
J 0
(2175 2550);
DISPLAY INVISIBLE (2175 2550);
FORCEPROP 1 LAST BODY_TYPE PLUMBING
J 0
(2175 2600);
DISPLAY 0.872340 (2175 2600);
PAINT GREEN (2175 2600);
DISPLAY INVISIBLE (2175 2600);
FORCEPROP 1 LAST HDL_TAP TRUE
J 0
(2500 2425);
DISPLAY 0.872340 (2500 2425);
DISPLAY INVISIBLE (2500 2425);
FORCEPROP 1 LAST PATH I134
J 0
(2173 2550);
DISPLAY 0.872340 (2173 2550);
PAINT GREEN (2173 2550);
DISPLAY INVISIBLE (2173 2550);
FORCEADD TAP..1
(2175 2750);
FORCEPROP 3 LASTPIN (2125 2750) SIG_NAME M_B_CPU1_SB_DQS_DP<3>
J 0
(2135 2760);
DISPLAY 0.659574 (2135 2760);
PAINT MONO (2135 2760);
DISPLAY INVISIBLE (2135 2760);
FORCEPROP 1 LASTPIN (2125 2750) BN 3
J 0
(2113 2758);
DISPLAY 0.680851 (2113 2758);
PAINT GREEN (2113 2758);
FORCEPROP 2 LAST CDS_LIB standard
J 0
(2175 2750);
PAINT MONO (2175 2750);
DISPLAY INVISIBLE (2175 2750);
FORCEPROP 1 LAST BODY_TYPE PLUMBING
J 0
(2175 2800);
DISPLAY 0.872340 (2175 2800);
PAINT GREEN (2175 2800);
DISPLAY INVISIBLE (2175 2800);
FORCEPROP 1 LAST HDL_TAP TRUE
J 0
(2500 2625);
DISPLAY 0.872340 (2500 2625);
DISPLAY INVISIBLE (2500 2625);
FORCEPROP 1 LAST PATH I135
J 0
(2173 2750);
DISPLAY 0.872340 (2173 2750);
PAINT GREEN (2173 2750);
DISPLAY INVISIBLE (2173 2750);
FORCEADD TAP..1
(2175 3050);
FORCEPROP 3 LASTPIN (2125 3050) SIG_NAME M_B_CPU1_SB_DQS_DP<6>
J 0
(2135 3060);
DISPLAY 0.659574 (2135 3060);
PAINT MONO (2135 3060);
DISPLAY INVISIBLE (2135 3060);
FORCEPROP 1 LASTPIN (2125 3050) BN 6
J 0
(2113 3058);
DISPLAY 0.680851 (2113 3058);
PAINT GREEN (2113 3058);
FORCEPROP 2 LAST CDS_LIB standard
J 0
(2175 3050);
DISPLAY INVISIBLE (2175 3050);
FORCEPROP 1 LAST BODY_TYPE PLUMBING
J 0
(2175 3100);
DISPLAY 0.872340 (2175 3100);
PAINT GREEN (2175 3100);
DISPLAY INVISIBLE (2175 3100);
FORCEPROP 1 LAST HDL_TAP TRUE
J 0
(2500 2925);
DISPLAY 0.872340 (2500 2925);
DISPLAY INVISIBLE (2500 2925);
FORCEPROP 1 LAST PATH I136
J 0
(2173 3050);
DISPLAY 0.872340 (2173 3050);
PAINT GREEN (2173 3050);
DISPLAY INVISIBLE (2173 3050);
FORCEADD TAP..1
(2175 2950);
FORCEPROP 3 LASTPIN (2125 2950) SIG_NAME M_B_CPU1_SB_DQS_DP<5>
J 0
(2135 2960);
DISPLAY 0.659574 (2135 2960);
PAINT MONO (2135 2960);
DISPLAY INVISIBLE (2135 2960);
FORCEPROP 1 LASTPIN (2125 2950) BN 5
J 0
(2113 2958);
DISPLAY 0.680851 (2113 2958);
PAINT GREEN (2113 2958);
FORCEPROP 2 LAST CDS_LIB standard
J 0
(2175 2950);
DISPLAY INVISIBLE (2175 2950);
FORCEPROP 1 LAST BODY_TYPE PLUMBING
J 0
(2175 3000);
DISPLAY 0.872340 (2175 3000);
PAINT GREEN (2175 3000);
DISPLAY INVISIBLE (2175 3000);
FORCEPROP 1 LAST HDL_TAP TRUE
J 0
(2500 2825);
DISPLAY 0.872340 (2500 2825);
DISPLAY INVISIBLE (2500 2825);
FORCEPROP 1 LAST PATH I137
J 0
(2173 2950);
DISPLAY 0.872340 (2173 2950);
PAINT GREEN (2173 2950);
DISPLAY INVISIBLE (2173 2950);
FORCEADD TAP..1
(2175 2850);
FORCEPROP 3 LASTPIN (2125 2850) SIG_NAME M_B_CPU1_SB_DQS_DP<4>
J 0
(2135 2860);
DISPLAY 0.659574 (2135 2860);
PAINT MONO (2135 2860);
DISPLAY INVISIBLE (2135 2860);
FORCEPROP 1 LASTPIN (2125 2850) BN 4
J 0
(2113 2858);
DISPLAY 0.680851 (2113 2858);
PAINT GREEN (2113 2858);
FORCEPROP 2 LAST CDS_LIB standard
J 0
(2175 2850);
PAINT MONO (2175 2850);
DISPLAY INVISIBLE (2175 2850);
FORCEPROP 1 LAST BODY_TYPE PLUMBING
J 0
(2175 2900);
DISPLAY 0.872340 (2175 2900);
PAINT GREEN (2175 2900);
DISPLAY INVISIBLE (2175 2900);
FORCEPROP 1 LAST HDL_TAP TRUE
J 0
(2500 2725);
DISPLAY 0.872340 (2500 2725);
DISPLAY INVISIBLE (2500 2725);
FORCEPROP 1 LAST PATH I138
J 0
(2173 2850);
DISPLAY 0.872340 (2173 2850);
PAINT GREEN (2173 2850);
DISPLAY INVISIBLE (2173 2850);
FORCEADD TAP..1
(2175 3250);
FORCEPROP 3 LASTPIN (2125 3250) SIG_NAME M_B_CPU1_SB_DQS_DP<8>
J 0
(2135 3260);
DISPLAY 0.659574 (2135 3260);
PAINT MONO (2135 3260);
DISPLAY INVISIBLE (2135 3260);
FORCEPROP 1 LASTPIN (2125 3250) BN 8
J 0
(2113 3258);
DISPLAY 0.680851 (2113 3258);
PAINT GREEN (2113 3258);
FORCEPROP 2 LAST CDS_LIB standard
J 0
(2175 3250);
DISPLAY INVISIBLE (2175 3250);
FORCEPROP 1 LAST BODY_TYPE PLUMBING
J 0
(2175 3300);
DISPLAY 0.872340 (2175 3300);
PAINT GREEN (2175 3300);
DISPLAY INVISIBLE (2175 3300);
FORCEPROP 1 LAST HDL_TAP TRUE
J 0
(2500 3125);
DISPLAY 0.872340 (2500 3125);
DISPLAY INVISIBLE (2500 3125);
FORCEPROP 1 LAST PATH I139
J 0
(2173 3250);
DISPLAY 0.872340 (2173 3250);
PAINT GREEN (2173 3250);
DISPLAY INVISIBLE (2173 3250);
FORCEADD OFFPAGE..3
R 2
(-3150 3025);
FORCEPROP 2 LAST $XR1 101 
J 0
(-3519 3025);
DISPLAY 0.638298 (-3519 3025);
PAINT MONO (-3519 3025);
FORCEPROP 2 LAST $XR0 52 
J 0
(-3399 3025);
DISPLAY 0.638298 (-3399 3025);
PAINT MONO (-3399 3025);
FORCEPROP 2 LAST CDS_LIB standard
J 0
(-3150 3025);
PAINT MONO (-3150 3025);
DISPLAY INVISIBLE (-3150 3025);
FORCEPROP 1 LAST OFFPAGE TRUE
J 2
(-3475 2900);
DISPLAY 0.872340 (-3475 2900);
DISPLAY INVISIBLE (-3475 2900);
FORCEPROP 1 LAST COMMENT_BODY TRUE
J 2
(-3100 2925);
DISPLAY 0.872340 (-3100 2925);
PAINT GREEN (-3100 2925);
DISPLAY INVISIBLE (-3100 2925);
FORCEPROP 2 LAST PATH I14
J 0
(-3100 3100);
DISPLAY 1.021277 (-3100 3100);
DISPLAY INVISIBLE (-3100 3100);
FORCEADD TAP..1
(2175 3150);
FORCEPROP 3 LASTPIN (2125 3150) SIG_NAME M_B_CPU1_SB_DQS_DP<7>
J 0
(2135 3160);
DISPLAY 0.659574 (2135 3160);
PAINT MONO (2135 3160);
DISPLAY INVISIBLE (2135 3160);
FORCEPROP 1 LASTPIN (2125 3150) BN 7
J 0
(2113 3158);
DISPLAY 0.680851 (2113 3158);
PAINT GREEN (2113 3158);
FORCEPROP 2 LAST CDS_LIB standard
J 0
(2175 3150);
DISPLAY INVISIBLE (2175 3150);
FORCEPROP 1 LAST BODY_TYPE PLUMBING
J 0
(2175 3200);
DISPLAY 0.872340 (2175 3200);
PAINT GREEN (2175 3200);
DISPLAY INVISIBLE (2175 3200);
FORCEPROP 1 LAST HDL_TAP TRUE
J 0
(2500 3025);
DISPLAY 0.872340 (2500 3025);
DISPLAY INVISIBLE (2500 3025);
FORCEPROP 1 LAST PATH I140
J 0
(2173 3150);
DISPLAY 0.872340 (2173 3150);
PAINT GREEN (2173 3150);
DISPLAY INVISIBLE (2173 3150);
FORCEADD TAP..1
(2175 3350);
FORCEPROP 3 LASTPIN (2125 3350) SIG_NAME M_B_CPU1_SB_DQS_DP<9>
J 0
(2135 3360);
DISPLAY 0.659574 (2135 3360);
PAINT MONO (2135 3360);
DISPLAY INVISIBLE (2135 3360);
FORCEPROP 1 LASTPIN (2125 3350) BN 9
J 0
(2113 3358);
DISPLAY 0.680851 (2113 3358);
PAINT GREEN (2113 3358);
FORCEPROP 2 LAST CDS_LIB standard
J 0
(2175 3350);
DISPLAY INVISIBLE (2175 3350);
FORCEPROP 1 LAST BODY_TYPE PLUMBING
J 0
(2175 3400);
DISPLAY 0.872340 (2175 3400);
PAINT GREEN (2175 3400);
DISPLAY INVISIBLE (2175 3400);
FORCEPROP 1 LAST HDL_TAP TRUE
J 0
(2500 3225);
DISPLAY 0.872340 (2500 3225);
DISPLAY INVISIBLE (2500 3225);
FORCEPROP 1 LAST PATH I141
J 0
(2173 3350);
DISPLAY 0.872340 (2173 3350);
PAINT GREEN (2173 3350);
DISPLAY INVISIBLE (2173 3350);
FORCEADD TAP..1
(2175 3500);
FORCEPROP 3 LASTPIN (2125 3500) SIG_NAME M_B_CPU1_SA_DQS_DP<0>
J 0
(2135 3510);
DISPLAY 0.659574 (2135 3510);
PAINT MONO (2135 3510);
DISPLAY INVISIBLE (2135 3510);
FORCEPROP 1 LASTPIN (2125 3500) BN 0
J 0
(2113 3508);
DISPLAY 0.680851 (2113 3508);
PAINT GREEN (2113 3508);
FORCEPROP 2 LAST CDS_LIB standard
J 0
(2175 3500);
PAINT MONO (2175 3500);
DISPLAY INVISIBLE (2175 3500);
FORCEPROP 1 LAST BODY_TYPE PLUMBING
J 0
(2175 3550);
DISPLAY 0.872340 (2175 3550);
PAINT GREEN (2175 3550);
DISPLAY INVISIBLE (2175 3550);
FORCEPROP 1 LAST HDL_TAP TRUE
J 0
(2500 3375);
DISPLAY 0.872340 (2500 3375);
DISPLAY INVISIBLE (2500 3375);
FORCEPROP 1 LAST PATH I142
J 0
(2173 3500);
DISPLAY 0.872340 (2173 3500);
PAINT GREEN (2173 3500);
DISPLAY INVISIBLE (2173 3500);
FORCEADD TAP..1
(2350 2600);
FORCEPROP 3 LASTPIN (2300 2600) SIG_NAME M_B_CPU1_SB_DQS_DN<2>
J 0
(2310 2610);
DISPLAY 0.659574 (2310 2610);
PAINT MONO (2310 2610);
DISPLAY INVISIBLE (2310 2610);
FORCEPROP 1 LASTPIN (2300 2600) BN 2
J 0
(2288 2608);
DISPLAY 0.680851 (2288 2608);
PAINT GREEN (2288 2608);
FORCEPROP 2 LAST CDS_LIB standard
J 0
(2350 2600);
DISPLAY INVISIBLE (2350 2600);
FORCEPROP 1 LAST BODY_TYPE PLUMBING
J 0
(2350 2650);
DISPLAY 0.872340 (2350 2650);
PAINT GREEN (2350 2650);
DISPLAY INVISIBLE (2350 2650);
FORCEPROP 1 LAST HDL_TAP TRUE
J 0
(2675 2475);
DISPLAY 0.872340 (2675 2475);
DISPLAY INVISIBLE (2675 2475);
FORCEPROP 1 LAST PATH I143
J 0
(2348 2600);
DISPLAY 0.872340 (2348 2600);
PAINT GREEN (2348 2600);
DISPLAY INVISIBLE (2348 2600);
FORCEADD TAP..1
(2350 2700);
FORCEPROP 3 LASTPIN (2300 2700) SIG_NAME M_B_CPU1_SB_DQS_DN<3>
J 0
(2310 2710);
DISPLAY 0.659574 (2310 2710);
PAINT MONO (2310 2710);
DISPLAY INVISIBLE (2310 2710);
FORCEPROP 1 LASTPIN (2300 2700) BN 3
J 0
(2288 2708);
DISPLAY 0.680851 (2288 2708);
PAINT GREEN (2288 2708);
FORCEPROP 2 LAST CDS_LIB standard
J 0
(2350 2700);
PAINT MONO (2350 2700);
DISPLAY INVISIBLE (2350 2700);
FORCEPROP 1 LAST BODY_TYPE PLUMBING
J 0
(2350 2750);
DISPLAY 0.872340 (2350 2750);
PAINT GREEN (2350 2750);
DISPLAY INVISIBLE (2350 2750);
FORCEPROP 1 LAST HDL_TAP TRUE
J 0
(2675 2575);
DISPLAY 0.872340 (2675 2575);
DISPLAY INVISIBLE (2675 2575);
FORCEPROP 1 LAST PATH I144
J 0
(2348 2700);
DISPLAY 0.872340 (2348 2700);
PAINT GREEN (2348 2700);
DISPLAY INVISIBLE (2348 2700);
FORCEADD TAP..1
(2350 2800);
FORCEPROP 3 LASTPIN (2300 2800) SIG_NAME M_B_CPU1_SB_DQS_DN<4>
J 0
(2310 2810);
DISPLAY 0.659574 (2310 2810);
PAINT MONO (2310 2810);
DISPLAY INVISIBLE (2310 2810);
FORCEPROP 1 LASTPIN (2300 2800) BN 4
J 0
(2288 2808);
DISPLAY 0.680851 (2288 2808);
PAINT GREEN (2288 2808);
FORCEPROP 2 LAST CDS_LIB standard
J 0
(2350 2800);
PAINT MONO (2350 2800);
DISPLAY INVISIBLE (2350 2800);
FORCEPROP 1 LAST BODY_TYPE PLUMBING
J 0
(2350 2850);
DISPLAY 0.872340 (2350 2850);
PAINT GREEN (2350 2850);
DISPLAY INVISIBLE (2350 2850);
FORCEPROP 1 LAST HDL_TAP TRUE
J 0
(2675 2675);
DISPLAY 0.872340 (2675 2675);
DISPLAY INVISIBLE (2675 2675);
FORCEPROP 1 LAST PATH I145
J 0
(2348 2800);
DISPLAY 0.872340 (2348 2800);
PAINT GREEN (2348 2800);
DISPLAY INVISIBLE (2348 2800);
FORCEADD TAP..1
(2350 2900);
FORCEPROP 3 LASTPIN (2300 2900) SIG_NAME M_B_CPU1_SB_DQS_DN<5>
J 0
(2310 2910);
DISPLAY 0.659574 (2310 2910);
PAINT MONO (2310 2910);
DISPLAY INVISIBLE (2310 2910);
FORCEPROP 1 LASTPIN (2300 2900) BN 5
J 0
(2288 2908);
DISPLAY 0.680851 (2288 2908);
PAINT GREEN (2288 2908);
FORCEPROP 2 LAST CDS_LIB standard
J 0
(2350 2900);
DISPLAY INVISIBLE (2350 2900);
FORCEPROP 1 LAST BODY_TYPE PLUMBING
J 0
(2350 2950);
DISPLAY 0.872340 (2350 2950);
PAINT GREEN (2350 2950);
DISPLAY INVISIBLE (2350 2950);
FORCEPROP 1 LAST HDL_TAP TRUE
J 0
(2675 2775);
DISPLAY 0.872340 (2675 2775);
DISPLAY INVISIBLE (2675 2775);
FORCEPROP 1 LAST PATH I146
J 0
(2348 2900);
DISPLAY 0.872340 (2348 2900);
PAINT GREEN (2348 2900);
DISPLAY INVISIBLE (2348 2900);
FORCEADD TAP..1
(2350 3000);
FORCEPROP 3 LASTPIN (2300 3000) SIG_NAME M_B_CPU1_SB_DQS_DN<6>
J 0
(2310 3010);
DISPLAY 0.659574 (2310 3010);
PAINT MONO (2310 3010);
DISPLAY INVISIBLE (2310 3010);
FORCEPROP 1 LASTPIN (2300 3000) BN 6
J 0
(2288 3008);
DISPLAY 0.680851 (2288 3008);
PAINT GREEN (2288 3008);
FORCEPROP 2 LAST CDS_LIB standard
J 0
(2350 3000);
DISPLAY INVISIBLE (2350 3000);
FORCEPROP 1 LAST BODY_TYPE PLUMBING
J 0
(2350 3050);
DISPLAY 0.872340 (2350 3050);
PAINT GREEN (2350 3050);
DISPLAY INVISIBLE (2350 3050);
FORCEPROP 1 LAST HDL_TAP TRUE
J 0
(2675 2875);
DISPLAY 0.872340 (2675 2875);
DISPLAY INVISIBLE (2675 2875);
FORCEPROP 1 LAST PATH I147
J 0
(2348 3000);
DISPLAY 0.872340 (2348 3000);
PAINT GREEN (2348 3000);
DISPLAY INVISIBLE (2348 3000);
FORCEADD TAP..1
(2350 3100);
FORCEPROP 3 LASTPIN (2300 3100) SIG_NAME M_B_CPU1_SB_DQS_DN<7>
J 0
(2310 3110);
DISPLAY 0.659574 (2310 3110);
PAINT MONO (2310 3110);
DISPLAY INVISIBLE (2310 3110);
FORCEPROP 1 LASTPIN (2300 3100) BN 7
J 0
(2288 3108);
DISPLAY 0.680851 (2288 3108);
PAINT GREEN (2288 3108);
FORCEPROP 2 LAST CDS_LIB standard
J 0
(2350 3100);
DISPLAY INVISIBLE (2350 3100);
FORCEPROP 1 LAST BODY_TYPE PLUMBING
J 0
(2350 3150);
DISPLAY 0.872340 (2350 3150);
PAINT GREEN (2350 3150);
DISPLAY INVISIBLE (2350 3150);
FORCEPROP 1 LAST HDL_TAP TRUE
J 0
(2675 2975);
DISPLAY 0.872340 (2675 2975);
DISPLAY INVISIBLE (2675 2975);
FORCEPROP 1 LAST PATH I148
J 0
(2348 3100);
DISPLAY 0.872340 (2348 3100);
PAINT GREEN (2348 3100);
DISPLAY INVISIBLE (2348 3100);
FORCEADD TAP..1
(2350 3200);
FORCEPROP 3 LASTPIN (2300 3200) SIG_NAME M_B_CPU1_SB_DQS_DN<8>
J 0
(2310 3210);
DISPLAY 0.659574 (2310 3210);
PAINT MONO (2310 3210);
DISPLAY INVISIBLE (2310 3210);
FORCEPROP 1 LASTPIN (2300 3200) BN 8
J 0
(2288 3208);
DISPLAY 0.680851 (2288 3208);
PAINT GREEN (2288 3208);
FORCEPROP 2 LAST CDS_LIB standard
J 0
(2350 3200);
DISPLAY INVISIBLE (2350 3200);
FORCEPROP 1 LAST BODY_TYPE PLUMBING
J 0
(2350 3250);
DISPLAY 0.872340 (2350 3250);
PAINT GREEN (2350 3250);
DISPLAY INVISIBLE (2350 3250);
FORCEPROP 1 LAST HDL_TAP TRUE
J 0
(2675 3075);
DISPLAY 0.872340 (2675 3075);
DISPLAY INVISIBLE (2675 3075);
FORCEPROP 1 LAST PATH I149
J 0
(2348 3200);
DISPLAY 0.872340 (2348 3200);
PAINT GREEN (2348 3200);
DISPLAY INVISIBLE (2348 3200);
FORCEADD OFFPAGE..1
(-3150 3150);
FORCEPROP 2 LAST $XR0 52 
J 0
(-3371 3150);
DISPLAY 0.638298 (-3371 3150);
PAINT MONO (-3371 3150);
FORCEPROP 2 LAST CDS_LIB standard
J 0
(-3150 3150);
PAINT MONO (-3150 3150);
DISPLAY INVISIBLE (-3150 3150);
FORCEPROP 1 LAST OFFPAGE TRUE
J 0
(-2825 3025);
DISPLAY 0.872340 (-2825 3025);
DISPLAY INVISIBLE (-2825 3025);
FORCEPROP 1 LAST COMMENT_BODY TRUE
J 0
(-3025 3050);
DISPLAY 0.872340 (-3025 3050);
PAINT GREEN (-3025 3050);
DISPLAY INVISIBLE (-3025 3050);
FORCEPROP 2 LAST PATH I15
J 0
(-3100 3225);
DISPLAY 1.021277 (-3100 3225);
DISPLAY INVISIBLE (-3100 3225);
FORCEADD TAP..1
(2350 3300);
FORCEPROP 3 LASTPIN (2300 3300) SIG_NAME M_B_CPU1_SB_DQS_DN<9>
J 0
(2310 3310);
DISPLAY 0.659574 (2310 3310);
PAINT MONO (2310 3310);
DISPLAY INVISIBLE (2310 3310);
FORCEPROP 1 LASTPIN (2300 3300) BN 9
J 0
(2288 3308);
DISPLAY 0.680851 (2288 3308);
PAINT GREEN (2288 3308);
FORCEPROP 2 LAST CDS_LIB standard
J 0
(2350 3300);
DISPLAY INVISIBLE (2350 3300);
FORCEPROP 1 LAST BODY_TYPE PLUMBING
J 0
(2350 3350);
DISPLAY 0.872340 (2350 3350);
PAINT GREEN (2350 3350);
DISPLAY INVISIBLE (2350 3350);
FORCEPROP 1 LAST HDL_TAP TRUE
J 0
(2675 3175);
DISPLAY 0.872340 (2675 3175);
DISPLAY INVISIBLE (2675 3175);
FORCEPROP 1 LAST PATH I150
J 0
(2348 3300);
DISPLAY 0.872340 (2348 3300);
PAINT GREEN (2348 3300);
DISPLAY INVISIBLE (2348 3300);
FORCEADD TAP..1
(2350 3550);
FORCEPROP 3 LASTPIN (2300 3550) SIG_NAME M_B_CPU1_SA_DQS_DN<1>
J 0
(2310 3560);
DISPLAY 0.659574 (2310 3560);
PAINT MONO (2310 3560);
DISPLAY INVISIBLE (2310 3560);
FORCEPROP 1 LASTPIN (2300 3550) BN 1
J 0
(2288 3558);
DISPLAY 0.680851 (2288 3558);
PAINT GREEN (2288 3558);
FORCEPROP 2 LAST CDS_LIB standard
J 0
(2350 3550);
DISPLAY INVISIBLE (2350 3550);
FORCEPROP 1 LAST BODY_TYPE PLUMBING
J 0
(2350 3600);
DISPLAY 0.872340 (2350 3600);
PAINT GREEN (2350 3600);
DISPLAY INVISIBLE (2350 3600);
FORCEPROP 1 LAST HDL_TAP TRUE
J 0
(2675 3425);
DISPLAY 0.872340 (2675 3425);
DISPLAY INVISIBLE (2675 3425);
FORCEPROP 1 LAST PATH I151
J 0
(2348 3550);
DISPLAY 0.872340 (2348 3550);
PAINT GREEN (2348 3550);
DISPLAY INVISIBLE (2348 3550);
FORCEADD TAP..1
(2350 3450);
FORCEPROP 3 LASTPIN (2300 3450) SIG_NAME M_B_CPU1_SA_DQS_DN<0>
J 0
(2310 3460);
DISPLAY 0.659574 (2310 3460);
PAINT MONO (2310 3460);
DISPLAY INVISIBLE (2310 3460);
FORCEPROP 1 LASTPIN (2300 3450) BN 0
J 0
(2288 3458);
DISPLAY 0.680851 (2288 3458);
PAINT GREEN (2288 3458);
FORCEPROP 2 LAST CDS_LIB standard
J 0
(2350 3450);
PAINT MONO (2350 3450);
DISPLAY INVISIBLE (2350 3450);
FORCEPROP 1 LAST BODY_TYPE PLUMBING
J 0
(2350 3500);
DISPLAY 0.872340 (2350 3500);
PAINT GREEN (2350 3500);
DISPLAY INVISIBLE (2350 3500);
FORCEPROP 1 LAST HDL_TAP TRUE
J 0
(2675 3325);
DISPLAY 0.872340 (2675 3325);
DISPLAY INVISIBLE (2675 3325);
FORCEPROP 1 LAST PATH I152
J 0
(2348 3450);
DISPLAY 0.872340 (2348 3450);
PAINT GREEN (2348 3450);
DISPLAY INVISIBLE (2348 3450);
FORCEADD TAP..1
(2175 3600);
FORCEPROP 3 LASTPIN (2125 3600) SIG_NAME M_B_CPU1_SA_DQS_DP<1>
J 0
(2135 3610);
DISPLAY 0.659574 (2135 3610);
PAINT MONO (2135 3610);
DISPLAY INVISIBLE (2135 3610);
FORCEPROP 1 LASTPIN (2125 3600) BN 1
J 0
(2113 3608);
DISPLAY 0.680851 (2113 3608);
PAINT GREEN (2113 3608);
FORCEPROP 2 LAST CDS_LIB standard
J 0
(2175 3600);
DISPLAY INVISIBLE (2175 3600);
FORCEPROP 1 LAST BODY_TYPE PLUMBING
J 0
(2175 3650);
DISPLAY 0.872340 (2175 3650);
PAINT GREEN (2175 3650);
DISPLAY INVISIBLE (2175 3650);
FORCEPROP 1 LAST HDL_TAP TRUE
J 0
(2500 3475);
DISPLAY 0.872340 (2500 3475);
DISPLAY INVISIBLE (2500 3475);
FORCEPROP 1 LAST PATH I153
J 0
(2173 3600);
DISPLAY 0.872340 (2173 3600);
PAINT GREEN (2173 3600);
DISPLAY INVISIBLE (2173 3600);
FORCEADD TAP..1
(2175 3800);
FORCEPROP 3 LASTPIN (2125 3800) SIG_NAME M_B_CPU1_SA_DQS_DP<3>
J 0
(2135 3810);
DISPLAY 0.659574 (2135 3810);
PAINT MONO (2135 3810);
DISPLAY INVISIBLE (2135 3810);
FORCEPROP 1 LASTPIN (2125 3800) BN 3
J 0
(2113 3808);
DISPLAY 0.680851 (2113 3808);
PAINT GREEN (2113 3808);
FORCEPROP 2 LAST CDS_LIB standard
J 0
(2175 3800);
PAINT MONO (2175 3800);
DISPLAY INVISIBLE (2175 3800);
FORCEPROP 1 LAST BODY_TYPE PLUMBING
J 0
(2175 3850);
DISPLAY 0.872340 (2175 3850);
PAINT GREEN (2175 3850);
DISPLAY INVISIBLE (2175 3850);
FORCEPROP 1 LAST HDL_TAP TRUE
J 0
(2500 3675);
DISPLAY 0.872340 (2500 3675);
DISPLAY INVISIBLE (2500 3675);
FORCEPROP 1 LAST PATH I154
J 0
(2173 3800);
DISPLAY 0.872340 (2173 3800);
PAINT GREEN (2173 3800);
DISPLAY INVISIBLE (2173 3800);
FORCEADD TAP..1
(2175 3700);
FORCEPROP 3 LASTPIN (2125 3700) SIG_NAME M_B_CPU1_SA_DQS_DP<2>
J 0
(2135 3710);
DISPLAY 0.659574 (2135 3710);
PAINT MONO (2135 3710);
DISPLAY INVISIBLE (2135 3710);
FORCEPROP 1 LASTPIN (2125 3700) BN 2
J 0
(2113 3708);
DISPLAY 0.680851 (2113 3708);
PAINT GREEN (2113 3708);
FORCEPROP 2 LAST CDS_LIB standard
J 0
(2175 3700);
DISPLAY INVISIBLE (2175 3700);
FORCEPROP 1 LAST BODY_TYPE PLUMBING
J 0
(2175 3750);
DISPLAY 0.872340 (2175 3750);
PAINT GREEN (2175 3750);
DISPLAY INVISIBLE (2175 3750);
FORCEPROP 1 LAST HDL_TAP TRUE
J 0
(2500 3575);
DISPLAY 0.872340 (2500 3575);
DISPLAY INVISIBLE (2500 3575);
FORCEPROP 1 LAST PATH I155
J 0
(2173 3700);
DISPLAY 0.872340 (2173 3700);
PAINT GREEN (2173 3700);
DISPLAY INVISIBLE (2173 3700);
FORCEADD TAP..1
(2175 4000);
FORCEPROP 3 LASTPIN (2125 4000) SIG_NAME M_B_CPU1_SA_DQS_DP<5>
J 0
(2135 4010);
DISPLAY 0.659574 (2135 4010);
PAINT MONO (2135 4010);
DISPLAY INVISIBLE (2135 4010);
FORCEPROP 1 LASTPIN (2125 4000) BN 5
J 0
(2113 4008);
DISPLAY 0.680851 (2113 4008);
PAINT GREEN (2113 4008);
FORCEPROP 2 LAST CDS_LIB standard
J 0
(2175 4000);
DISPLAY INVISIBLE (2175 4000);
FORCEPROP 1 LAST BODY_TYPE PLUMBING
J 0
(2175 4050);
DISPLAY 0.872340 (2175 4050);
PAINT GREEN (2175 4050);
DISPLAY INVISIBLE (2175 4050);
FORCEPROP 1 LAST HDL_TAP TRUE
J 0
(2500 3875);
DISPLAY 0.872340 (2500 3875);
DISPLAY INVISIBLE (2500 3875);
FORCEPROP 1 LAST PATH I156
J 0
(2173 4000);
DISPLAY 0.872340 (2173 4000);
PAINT GREEN (2173 4000);
DISPLAY INVISIBLE (2173 4000);
FORCEADD TAP..1
(2175 3900);
FORCEPROP 3 LASTPIN (2125 3900) SIG_NAME M_B_CPU1_SA_DQS_DP<4>
J 0
(2135 3910);
DISPLAY 0.659574 (2135 3910);
PAINT MONO (2135 3910);
DISPLAY INVISIBLE (2135 3910);
FORCEPROP 1 LASTPIN (2125 3900) BN 4
J 0
(2113 3908);
DISPLAY 0.680851 (2113 3908);
PAINT GREEN (2113 3908);
FORCEPROP 2 LAST CDS_LIB standard
J 0
(2175 3900);
PAINT MONO (2175 3900);
DISPLAY INVISIBLE (2175 3900);
FORCEPROP 1 LAST BODY_TYPE PLUMBING
J 0
(2175 3950);
DISPLAY 0.872340 (2175 3950);
PAINT GREEN (2175 3950);
DISPLAY INVISIBLE (2175 3950);
FORCEPROP 1 LAST HDL_TAP TRUE
J 0
(2500 3775);
DISPLAY 0.872340 (2500 3775);
DISPLAY INVISIBLE (2500 3775);
FORCEPROP 1 LAST PATH I157
J 0
(2173 3900);
DISPLAY 0.872340 (2173 3900);
PAINT GREEN (2173 3900);
DISPLAY INVISIBLE (2173 3900);
FORCEADD TAP..1
(2175 4300);
FORCEPROP 3 LASTPIN (2125 4300) SIG_NAME M_B_CPU1_SA_DQS_DP<8>
J 0
(2135 4310);
DISPLAY 0.659574 (2135 4310);
PAINT MONO (2135 4310);
DISPLAY INVISIBLE (2135 4310);
FORCEPROP 1 LASTPIN (2125 4300) BN 8
J 0
(2113 4308);
DISPLAY 0.680851 (2113 4308);
PAINT GREEN (2113 4308);
FORCEPROP 2 LAST CDS_LIB standard
J 0
(2175 4300);
DISPLAY INVISIBLE (2175 4300);
FORCEPROP 1 LAST BODY_TYPE PLUMBING
J 0
(2175 4350);
DISPLAY 0.872340 (2175 4350);
PAINT GREEN (2175 4350);
DISPLAY INVISIBLE (2175 4350);
FORCEPROP 1 LAST HDL_TAP TRUE
J 0
(2500 4175);
DISPLAY 0.872340 (2500 4175);
DISPLAY INVISIBLE (2500 4175);
FORCEPROP 1 LAST PATH I158
J 0
(2173 4300);
DISPLAY 0.872340 (2173 4300);
PAINT GREEN (2173 4300);
DISPLAY INVISIBLE (2173 4300);
FORCEADD TAP..1
(2175 4200);
FORCEPROP 3 LASTPIN (2125 4200) SIG_NAME M_B_CPU1_SA_DQS_DP<7>
J 0
(2135 4210);
DISPLAY 0.659574 (2135 4210);
PAINT MONO (2135 4210);
DISPLAY INVISIBLE (2135 4210);
FORCEPROP 1 LASTPIN (2125 4200) BN 7
J 0
(2113 4208);
DISPLAY 0.680851 (2113 4208);
PAINT GREEN (2113 4208);
FORCEPROP 2 LAST CDS_LIB standard
J 0
(2175 4200);
DISPLAY INVISIBLE (2175 4200);
FORCEPROP 1 LAST BODY_TYPE PLUMBING
J 0
(2175 4250);
DISPLAY 0.872340 (2175 4250);
PAINT GREEN (2175 4250);
DISPLAY INVISIBLE (2175 4250);
FORCEPROP 1 LAST HDL_TAP TRUE
J 0
(2500 4075);
DISPLAY 0.872340 (2500 4075);
DISPLAY INVISIBLE (2500 4075);
FORCEPROP 1 LAST PATH I159
J 0
(2173 4200);
DISPLAY 0.872340 (2173 4200);
PAINT GREEN (2173 4200);
DISPLAY INVISIBLE (2173 4200);
FORCEADD OFFPAGE..1
(-3150 3250);
FORCEPROP 2 LAST $XR0 52 
J 0
(-3371 3250);
DISPLAY 0.638298 (-3371 3250);
PAINT MONO (-3371 3250);
FORCEPROP 2 LAST CDS_LIB standard
J 0
(-3150 3250);
PAINT MONO (-3150 3250);
DISPLAY INVISIBLE (-3150 3250);
FORCEPROP 1 LAST OFFPAGE TRUE
J 0
(-2825 3125);
DISPLAY 0.872340 (-2825 3125);
DISPLAY INVISIBLE (-2825 3125);
FORCEPROP 1 LAST COMMENT_BODY TRUE
J 0
(-3025 3150);
DISPLAY 0.872340 (-3025 3150);
PAINT GREEN (-3025 3150);
DISPLAY INVISIBLE (-3025 3150);
FORCEPROP 2 LAST PATH I16
J 0
(-3100 3325);
DISPLAY 1.021277 (-3100 3325);
DISPLAY INVISIBLE (-3100 3325);
FORCEADD TAP..1
(2175 4100);
FORCEPROP 3 LASTPIN (2125 4100) SIG_NAME M_B_CPU1_SA_DQS_DP<6>
J 0
(2135 4110);
DISPLAY 0.659574 (2135 4110);
PAINT MONO (2135 4110);
DISPLAY INVISIBLE (2135 4110);
FORCEPROP 1 LASTPIN (2125 4100) BN 6
J 0
(2113 4108);
DISPLAY 0.680851 (2113 4108);
PAINT GREEN (2113 4108);
FORCEPROP 2 LAST CDS_LIB standard
J 0
(2175 4100);
DISPLAY INVISIBLE (2175 4100);
FORCEPROP 1 LAST BODY_TYPE PLUMBING
J 0
(2175 4150);
DISPLAY 0.872340 (2175 4150);
PAINT GREEN (2175 4150);
DISPLAY INVISIBLE (2175 4150);
FORCEPROP 1 LAST HDL_TAP TRUE
J 0
(2500 3975);
DISPLAY 0.872340 (2500 3975);
DISPLAY INVISIBLE (2500 3975);
FORCEPROP 1 LAST PATH I160
J 0
(2173 4100);
DISPLAY 0.872340 (2173 4100);
PAINT GREEN (2173 4100);
DISPLAY INVISIBLE (2173 4100);
FORCEADD TAP..1
(2175 4400);
FORCEPROP 3 LASTPIN (2125 4400) SIG_NAME M_B_CPU1_SA_DQS_DP<9>
J 0
(2135 4410);
DISPLAY 0.659574 (2135 4410);
PAINT MONO (2135 4410);
DISPLAY INVISIBLE (2135 4410);
FORCEPROP 1 LASTPIN (2125 4400) BN 9
J 0
(2113 4408);
DISPLAY 0.680851 (2113 4408);
PAINT GREEN (2113 4408);
FORCEPROP 2 LAST CDS_LIB standard
J 0
(2175 4400);
DISPLAY INVISIBLE (2175 4400);
FORCEPROP 1 LAST BODY_TYPE PLUMBING
J 0
(2175 4450);
DISPLAY 0.872340 (2175 4450);
PAINT GREEN (2175 4450);
DISPLAY INVISIBLE (2175 4450);
FORCEPROP 1 LAST HDL_TAP TRUE
J 0
(2500 4275);
DISPLAY 0.872340 (2500 4275);
DISPLAY INVISIBLE (2500 4275);
FORCEPROP 1 LAST PATH I161
J 0
(2173 4400);
DISPLAY 0.872340 (2173 4400);
PAINT GREEN (2173 4400);
DISPLAY INVISIBLE (2173 4400);
FORCEADD TAP..1
(2350 3650);
FORCEPROP 3 LASTPIN (2300 3650) SIG_NAME M_B_CPU1_SA_DQS_DN<2>
J 0
(2310 3660);
DISPLAY 0.659574 (2310 3660);
PAINT MONO (2310 3660);
DISPLAY INVISIBLE (2310 3660);
FORCEPROP 1 LASTPIN (2300 3650) BN 2
J 0
(2288 3658);
DISPLAY 0.680851 (2288 3658);
PAINT GREEN (2288 3658);
FORCEPROP 2 LAST CDS_LIB standard
J 0
(2350 3650);
DISPLAY INVISIBLE (2350 3650);
FORCEPROP 1 LAST BODY_TYPE PLUMBING
J 0
(2350 3700);
DISPLAY 0.872340 (2350 3700);
PAINT GREEN (2350 3700);
DISPLAY INVISIBLE (2350 3700);
FORCEPROP 1 LAST HDL_TAP TRUE
J 0
(2675 3525);
DISPLAY 0.872340 (2675 3525);
DISPLAY INVISIBLE (2675 3525);
FORCEPROP 1 LAST PATH I162
J 0
(2348 3650);
DISPLAY 0.872340 (2348 3650);
PAINT GREEN (2348 3650);
DISPLAY INVISIBLE (2348 3650);
FORCEADD TAP..1
(2350 3750);
FORCEPROP 3 LASTPIN (2300 3750) SIG_NAME M_B_CPU1_SA_DQS_DN<3>
J 0
(2310 3760);
DISPLAY 0.659574 (2310 3760);
PAINT MONO (2310 3760);
DISPLAY INVISIBLE (2310 3760);
FORCEPROP 1 LASTPIN (2300 3750) BN 3
J 0
(2288 3758);
DISPLAY 0.680851 (2288 3758);
PAINT GREEN (2288 3758);
FORCEPROP 2 LAST CDS_LIB standard
J 0
(2350 3750);
PAINT MONO (2350 3750);
DISPLAY INVISIBLE (2350 3750);
FORCEPROP 1 LAST BODY_TYPE PLUMBING
J 0
(2350 3800);
DISPLAY 0.872340 (2350 3800);
PAINT GREEN (2350 3800);
DISPLAY INVISIBLE (2350 3800);
FORCEPROP 1 LAST HDL_TAP TRUE
J 0
(2675 3625);
DISPLAY 0.872340 (2675 3625);
DISPLAY INVISIBLE (2675 3625);
FORCEPROP 1 LAST PATH I163
J 0
(2348 3750);
DISPLAY 0.872340 (2348 3750);
PAINT GREEN (2348 3750);
DISPLAY INVISIBLE (2348 3750);
FORCEADD TAP..1
(2350 3850);
FORCEPROP 3 LASTPIN (2300 3850) SIG_NAME M_B_CPU1_SA_DQS_DN<4>
J 0
(2310 3860);
DISPLAY 0.659574 (2310 3860);
PAINT MONO (2310 3860);
DISPLAY INVISIBLE (2310 3860);
FORCEPROP 1 LASTPIN (2300 3850) BN 4
J 0
(2288 3858);
DISPLAY 0.680851 (2288 3858);
PAINT GREEN (2288 3858);
FORCEPROP 2 LAST CDS_LIB standard
J 0
(2350 3850);
PAINT MONO (2350 3850);
DISPLAY INVISIBLE (2350 3850);
FORCEPROP 1 LAST BODY_TYPE PLUMBING
J 0
(2350 3900);
DISPLAY 0.872340 (2350 3900);
PAINT GREEN (2350 3900);
DISPLAY INVISIBLE (2350 3900);
FORCEPROP 1 LAST HDL_TAP TRUE
J 0
(2675 3725);
DISPLAY 0.872340 (2675 3725);
DISPLAY INVISIBLE (2675 3725);
FORCEPROP 1 LAST PATH I164
J 0
(2348 3850);
DISPLAY 0.872340 (2348 3850);
PAINT GREEN (2348 3850);
DISPLAY INVISIBLE (2348 3850);
FORCEADD TAP..1
(2350 3950);
FORCEPROP 3 LASTPIN (2300 3950) SIG_NAME M_B_CPU1_SA_DQS_DN<5>
J 0
(2310 3960);
DISPLAY 0.659574 (2310 3960);
PAINT MONO (2310 3960);
DISPLAY INVISIBLE (2310 3960);
FORCEPROP 1 LASTPIN (2300 3950) BN 5
J 0
(2288 3958);
DISPLAY 0.680851 (2288 3958);
PAINT GREEN (2288 3958);
FORCEPROP 2 LAST CDS_LIB standard
J 0
(2350 3950);
DISPLAY INVISIBLE (2350 3950);
FORCEPROP 1 LAST BODY_TYPE PLUMBING
J 0
(2350 4000);
DISPLAY 0.872340 (2350 4000);
PAINT GREEN (2350 4000);
DISPLAY INVISIBLE (2350 4000);
FORCEPROP 1 LAST HDL_TAP TRUE
J 0
(2675 3825);
DISPLAY 0.872340 (2675 3825);
DISPLAY INVISIBLE (2675 3825);
FORCEPROP 1 LAST PATH I165
J 0
(2348 3950);
DISPLAY 0.872340 (2348 3950);
PAINT GREEN (2348 3950);
DISPLAY INVISIBLE (2348 3950);
FORCEADD TAP..1
(2350 4050);
FORCEPROP 3 LASTPIN (2300 4050) SIG_NAME M_B_CPU1_SA_DQS_DN<6>
J 0
(2310 4060);
DISPLAY 0.659574 (2310 4060);
PAINT MONO (2310 4060);
DISPLAY INVISIBLE (2310 4060);
FORCEPROP 1 LASTPIN (2300 4050) BN 6
J 0
(2288 4058);
DISPLAY 0.680851 (2288 4058);
PAINT GREEN (2288 4058);
FORCEPROP 2 LAST CDS_LIB standard
J 0
(2350 4050);
DISPLAY INVISIBLE (2350 4050);
FORCEPROP 1 LAST BODY_TYPE PLUMBING
J 0
(2350 4100);
DISPLAY 0.872340 (2350 4100);
PAINT GREEN (2350 4100);
DISPLAY INVISIBLE (2350 4100);
FORCEPROP 1 LAST HDL_TAP TRUE
J 0
(2675 3925);
DISPLAY 0.872340 (2675 3925);
DISPLAY INVISIBLE (2675 3925);
FORCEPROP 1 LAST PATH I166
J 0
(2348 4050);
DISPLAY 0.872340 (2348 4050);
PAINT GREEN (2348 4050);
DISPLAY INVISIBLE (2348 4050);
FORCEADD TAP..1
(2350 4150);
FORCEPROP 3 LASTPIN (2300 4150) SIG_NAME M_B_CPU1_SA_DQS_DN<7>
J 0
(2310 4160);
DISPLAY 0.659574 (2310 4160);
PAINT MONO (2310 4160);
DISPLAY INVISIBLE (2310 4160);
FORCEPROP 1 LASTPIN (2300 4150) BN 7
J 0
(2288 4158);
DISPLAY 0.680851 (2288 4158);
PAINT GREEN (2288 4158);
FORCEPROP 2 LAST CDS_LIB standard
J 0
(2350 4150);
DISPLAY INVISIBLE (2350 4150);
FORCEPROP 1 LAST BODY_TYPE PLUMBING
J 0
(2350 4200);
DISPLAY 0.872340 (2350 4200);
PAINT GREEN (2350 4200);
DISPLAY INVISIBLE (2350 4200);
FORCEPROP 1 LAST HDL_TAP TRUE
J 0
(2675 4025);
DISPLAY 0.872340 (2675 4025);
DISPLAY INVISIBLE (2675 4025);
FORCEPROP 1 LAST PATH I167
J 0
(2348 4150);
DISPLAY 0.872340 (2348 4150);
PAINT GREEN (2348 4150);
DISPLAY INVISIBLE (2348 4150);
FORCEADD TAP..1
(2350 4250);
FORCEPROP 3 LASTPIN (2300 4250) SIG_NAME M_B_CPU1_SA_DQS_DN<8>
J 0
(2310 4260);
DISPLAY 0.659574 (2310 4260);
PAINT MONO (2310 4260);
DISPLAY INVISIBLE (2310 4260);
FORCEPROP 1 LASTPIN (2300 4250) BN 8
J 0
(2288 4258);
DISPLAY 0.680851 (2288 4258);
PAINT GREEN (2288 4258);
FORCEPROP 2 LAST CDS_LIB standard
J 0
(2350 4250);
DISPLAY INVISIBLE (2350 4250);
FORCEPROP 1 LAST BODY_TYPE PLUMBING
J 0
(2350 4300);
DISPLAY 0.872340 (2350 4300);
PAINT GREEN (2350 4300);
DISPLAY INVISIBLE (2350 4300);
FORCEPROP 1 LAST HDL_TAP TRUE
J 0
(2675 4125);
DISPLAY 0.872340 (2675 4125);
DISPLAY INVISIBLE (2675 4125);
FORCEPROP 1 LAST PATH I168
J 0
(2348 4250);
DISPLAY 0.872340 (2348 4250);
PAINT GREEN (2348 4250);
DISPLAY INVISIBLE (2348 4250);
FORCEADD TAP..1
(2350 4350);
FORCEPROP 3 LASTPIN (2300 4350) SIG_NAME M_B_CPU1_SA_DQS_DN<9>
J 0
(2310 4360);
DISPLAY 0.659574 (2310 4360);
PAINT MONO (2310 4360);
DISPLAY INVISIBLE (2310 4360);
FORCEPROP 1 LASTPIN (2300 4350) BN 9
J 0
(2288 4358);
DISPLAY 0.680851 (2288 4358);
PAINT GREEN (2288 4358);
FORCEPROP 2 LAST CDS_LIB standard
J 0
(2350 4350);
DISPLAY INVISIBLE (2350 4350);
FORCEPROP 1 LAST BODY_TYPE PLUMBING
J 0
(2350 4400);
DISPLAY 0.872340 (2350 4400);
PAINT GREEN (2350 4400);
DISPLAY INVISIBLE (2350 4400);
FORCEPROP 1 LAST HDL_TAP TRUE
J 0
(2675 4225);
DISPLAY 0.872340 (2675 4225);
DISPLAY INVISIBLE (2675 4225);
FORCEPROP 1 LAST PATH I169
J 0
(2348 4350);
DISPLAY 0.872340 (2348 4350);
PAINT GREEN (2348 4350);
DISPLAY INVISIBLE (2348 4350);
FORCEADD OFFPAGE..1
(-3150 3100);
FORCEPROP 2 LAST $XR0 52 
J 0
(-3371 3100);
DISPLAY 0.638298 (-3371 3100);
PAINT MONO (-3371 3100);
FORCEPROP 2 LAST CDS_LIB standard
J 0
(-3150 3100);
PAINT MONO (-3150 3100);
DISPLAY INVISIBLE (-3150 3100);
FORCEPROP 1 LAST OFFPAGE TRUE
J 0
(-2825 2975);
DISPLAY 0.872340 (-2825 2975);
DISPLAY INVISIBLE (-2825 2975);
FORCEPROP 1 LAST COMMENT_BODY TRUE
J 0
(-3025 3000);
DISPLAY 0.872340 (-3025 3000);
PAINT GREEN (-3025 3000);
DISPLAY INVISIBLE (-3025 3000);
FORCEPROP 2 LAST PATH I17
J 0
(-3100 3175);
DISPLAY 1.021277 (-3100 3175);
DISPLAY INVISIBLE (-3100 3175);
FORCEADD OFFPAGE..2
(3300 3325);
FORCEPROP 2 LAST $XR1 101 
J 0
(3579 3325);
DISPLAY 0.638298 (3579 3325);
PAINT MONO (3579 3325);
FORCEPROP 2 LAST $XR0 52 
J 0
(3489 3325);
DISPLAY 0.638298 (3489 3325);
PAINT MONO (3489 3325);
FORCEPROP 2 LAST CDS_LIB standard
J 0
(3300 3325);
PAINT MONO (3300 3325);
DISPLAY INVISIBLE (3300 3325);
FORCEPROP 1 LAST OFFPAGE TRUE
J 0
(3625 3200);
DISPLAY 1.170213 (3625 3200);
PAINT GREEN (3625 3200);
DISPLAY INVISIBLE (3625 3200);
FORCEPROP 1 LAST COMMENT_BODY TRUE
J 0
(3255 3230);
DISPLAY 1.170213 (3255 3230);
PAINT GREEN (3255 3230);
DISPLAY INVISIBLE (3255 3230);
FORCEPROP 2 LAST PATH I170
J 0
(3475 3400);
DISPLAY 1.021277 (3475 3400);
DISPLAY INVISIBLE (3475 3400);
FORCEADD OFFPAGE..2
(3300 3375);
FORCEPROP 2 LAST $XR1 101 
J 0
(3579 3375);
DISPLAY 0.638298 (3579 3375);
PAINT MONO (3579 3375);
FORCEPROP 2 LAST $XR0 52 
J 0
(3489 3375);
DISPLAY 0.638298 (3489 3375);
PAINT MONO (3489 3375);
FORCEPROP 2 LAST CDS_LIB standard
J 0
(3300 3375);
PAINT MONO (3300 3375);
DISPLAY INVISIBLE (3300 3375);
FORCEPROP 1 LAST OFFPAGE TRUE
J 0
(3625 3250);
DISPLAY 1.170213 (3625 3250);
PAINT GREEN (3625 3250);
DISPLAY INVISIBLE (3625 3250);
FORCEPROP 1 LAST COMMENT_BODY TRUE
J 0
(3255 3280);
DISPLAY 1.170213 (3255 3280);
PAINT GREEN (3255 3280);
DISPLAY INVISIBLE (3255 3280);
FORCEPROP 2 LAST PATH I171
J 0
(3475 3450);
DISPLAY 1.021277 (3475 3450);
DISPLAY INVISIBLE (3475 3450);
FORCEADD OFFPAGE..2
(3300 4425);
FORCEPROP 2 LAST $XR1 101 
J 0
(3579 4425);
DISPLAY 0.638298 (3579 4425);
PAINT MONO (3579 4425);
FORCEPROP 2 LAST $XR0 52 
J 0
(3489 4425);
DISPLAY 0.638298 (3489 4425);
PAINT MONO (3489 4425);
FORCEPROP 2 LAST CDS_LIB standard
J 0
(3300 4425);
PAINT MONO (3300 4425);
DISPLAY INVISIBLE (3300 4425);
FORCEPROP 1 LAST OFFPAGE TRUE
J 0
(3625 4300);
DISPLAY 1.170213 (3625 4300);
PAINT GREEN (3625 4300);
DISPLAY INVISIBLE (3625 4300);
FORCEPROP 1 LAST COMMENT_BODY TRUE
J 0
(3255 4330);
DISPLAY 1.170213 (3255 4330);
PAINT GREEN (3255 4330);
DISPLAY INVISIBLE (3255 4330);
FORCEPROP 2 LAST PATH I172
J 0
(3475 4500);
DISPLAY 1.021277 (3475 4500);
DISPLAY INVISIBLE (3475 4500);
FORCEADD OFFPAGE..2
(3300 4375);
FORCEPROP 2 LAST $XR1 101 
J 0
(3579 4375);
DISPLAY 0.638298 (3579 4375);
PAINT MONO (3579 4375);
FORCEPROP 2 LAST $XR0 52 
J 0
(3489 4375);
DISPLAY 0.638298 (3489 4375);
PAINT MONO (3489 4375);
FORCEPROP 2 LAST CDS_LIB standard
J 0
(3300 4375);
PAINT MONO (3300 4375);
DISPLAY INVISIBLE (3300 4375);
FORCEPROP 1 LAST OFFPAGE TRUE
J 0
(3625 4250);
DISPLAY 1.170213 (3625 4250);
PAINT GREEN (3625 4250);
DISPLAY INVISIBLE (3625 4250);
FORCEPROP 1 LAST COMMENT_BODY TRUE
J 0
(3255 4280);
DISPLAY 1.170213 (3255 4280);
PAINT GREEN (3255 4280);
DISPLAY INVISIBLE (3255 4280);
FORCEPROP 2 LAST PATH I173
J 0
(3475 4450);
DISPLAY 1.021277 (3475 4450);
DISPLAY INVISIBLE (3475 4450);
FORCEADD UNIVERSAL_GND..1
(3850 700);
FORCEPROP 3 LASTPIN (3850 750) SIG_NAME GND\g
J 0
(3860 760);
DISPLAY 0.659574 (3860 760);
PAINT MONO (3860 760);
DISPLAY INVISIBLE (3860 760);
FORCEPROP 1 LAST PATH I174
J 0
(3925 700);
DISPLAY 0.872340 (3925 700);
PAINT AQUA (3925 700);
DISPLAY INVISIBLE (3925 700);
FORCEPROP 1 LAST HDL_POWER GND
J 1
(3875 625);
DISPLAY 0.872340 (3875 625);
PAINT GREEN (3875 625);
DISPLAY INVISIBLE (3875 625);
FORCEPROP 2 LAST CDS_LIB logical_power
J 0
(3850 700);
PAINT MONO (3850 700);
DISPLAY INVISIBLE (3850 700);
FORCEADD SCONN288_ADR50017P130CC..3
(4700 2775);
FORCEPROP 1 LAST PART_NUMBER DFHST8FS461
J 0
(4245 4699);
DISPLAY 0.723404 (4245 4699);
PAINT GREEN (4245 4699);
DISPLAY INVISIBLE (4245 4699);
FORCEPROP 1 LAST MATERIAL IO
J 0
(4245 4572);
DISPLAY 0.723404 (4245 4572);
PAINT GREEN (4245 4572);
FORCEPROP 2 LAST PART_TYPE SMLF
J 0
(4250 4850);
DISPLAY 1.021277 (4250 4850);
FORCEPROP 2 LAST VALUE SCONN288_ADR50017-P130CC
J 0
(4250 4800);
DISPLAY 1.021277 (4250 4800);
FORCEPROP 1 LAST $LOCATION J19
J 0
(4250 4750);
DISPLAY 0.723404 (4250 4750);
PAINT GREEN (4250 4750);
FORCEPROP 0 LASTPIN (5300 1150) $PN G1
J 0
(5310 1160);
DISPLAY 0.680851 (5310 1160);
PAINT MONO (5310 1160);
FORCEPROP 0 LASTPIN (5300 1100) $PN G2
J 0
(5310 1110);
DISPLAY 0.680851 (5310 1110);
PAINT MONO (5310 1110);
FORCEPROP 0 LASTPIN (5300 1050) $PN G3
J 0
(5310 1060);
DISPLAY 0.680851 (5310 1060);
PAINT MONO (5310 1060);
FORCEPROP 0 LASTPIN (4100 4300) $PN 1
J 2
(4090 4310);
DISPLAY 0.680851 (4090 4310);
PAINT MONO (4090 4310);
FORCEPROP 0 LASTPIN (4100 4350) $PN 145
J 2
(4090 4360);
DISPLAY 0.680851 (4090 4360);
PAINT MONO (4090 4360);
FORCEPROP 0 LASTPIN (4100 4400) $PN 146
J 2
(4090 4410);
DISPLAY 0.680851 (4090 4410);
PAINT MONO (4090 4410);
FORCEPROP 0 LASTPIN (5300 1250) $PN 6
J 0
(5310 1260);
DISPLAY 0.680851 (5310 1260);
PAINT MONO (5310 1260);
FORCEPROP 0 LASTPIN (5300 1300) $PN 8
J 0
(5310 1310);
DISPLAY 0.680851 (5310 1310);
PAINT MONO (5310 1310);
FORCEPROP 0 LASTPIN (5300 1350) $PN 10
J 0
(5310 1360);
DISPLAY 0.680851 (5310 1360);
PAINT MONO (5310 1360);
FORCEPROP 0 LASTPIN (5300 1400) $PN 13
J 0
(5310 1410);
DISPLAY 0.680851 (5310 1410);
PAINT MONO (5310 1410);
FORCEPROP 0 LASTPIN (5300 1450) $PN 15
J 0
(5310 1460);
DISPLAY 0.680851 (5310 1460);
PAINT MONO (5310 1460);
FORCEPROP 0 LASTPIN (5300 1500) $PN 17
J 0
(5310 1510);
DISPLAY 0.680851 (5310 1510);
PAINT MONO (5310 1510);
FORCEPROP 0 LASTPIN (5300 1550) $PN 19
J 0
(5310 1560);
DISPLAY 0.680851 (5310 1560);
PAINT MONO (5310 1560);
FORCEPROP 0 LASTPIN (5300 1600) $PN 21
J 0
(5310 1610);
DISPLAY 0.680851 (5310 1610);
PAINT MONO (5310 1610);
FORCEPROP 0 LASTPIN (5300 1650) $PN 24
J 0
(5310 1660);
DISPLAY 0.680851 (5310 1660);
PAINT MONO (5310 1660);
FORCEPROP 0 LASTPIN (5300 1700) $PN 26
J 0
(5310 1710);
DISPLAY 0.680851 (5310 1710);
PAINT MONO (5310 1710);
FORCEPROP 0 LASTPIN (5300 1750) $PN 28
J 0
(5310 1760);
DISPLAY 0.680851 (5310 1760);
PAINT MONO (5310 1760);
FORCEPROP 0 LASTPIN (5300 1800) $PN 30
J 0
(5310 1810);
DISPLAY 0.680851 (5310 1810);
PAINT MONO (5310 1810);
FORCEPROP 0 LASTPIN (5300 1850) $PN 32
J 0
(5310 1860);
DISPLAY 0.680851 (5310 1860);
PAINT MONO (5310 1860);
FORCEPROP 0 LASTPIN (5300 1900) $PN 35
J 0
(5310 1910);
DISPLAY 0.680851 (5310 1910);
PAINT MONO (5310 1910);
FORCEPROP 0 LASTPIN (5300 1950) $PN 37
J 0
(5310 1960);
DISPLAY 0.680851 (5310 1960);
PAINT MONO (5310 1960);
FORCEPROP 0 LASTPIN (5300 2000) $PN 39
J 0
(5310 2010);
DISPLAY 0.680851 (5310 2010);
PAINT MONO (5310 2010);
FORCEPROP 0 LASTPIN (5300 2050) $PN 41
J 0
(5310 2060);
DISPLAY 0.680851 (5310 2060);
PAINT MONO (5310 2060);
FORCEPROP 0 LASTPIN (5300 2100) $PN 43
J 0
(5310 2110);
DISPLAY 0.680851 (5310 2110);
PAINT MONO (5310 2110);
FORCEPROP 0 LASTPIN (5300 2150) $PN 46
J 0
(5310 2160);
DISPLAY 0.680851 (5310 2160);
PAINT MONO (5310 2160);
FORCEPROP 0 LASTPIN (5300 2200) $PN 48
J 0
(5310 2210);
DISPLAY 0.680851 (5310 2210);
PAINT MONO (5310 2210);
FORCEPROP 0 LASTPIN (5300 2250) $PN 50
J 0
(5310 2260);
DISPLAY 0.680851 (5310 2260);
PAINT MONO (5310 2260);
FORCEPROP 0 LASTPIN (5300 2300) $PN 52
J 0
(5310 2310);
DISPLAY 0.680851 (5310 2310);
PAINT MONO (5310 2310);
FORCEPROP 0 LASTPIN (5300 2350) $PN 54
J 0
(5310 2360);
DISPLAY 0.680851 (5310 2360);
PAINT MONO (5310 2360);
FORCEPROP 0 LASTPIN (5300 2400) $PN 57
J 0
(5310 2410);
DISPLAY 0.680851 (5310 2410);
PAINT MONO (5310 2410);
FORCEPROP 0 LASTPIN (5300 2450) $PN 59
J 0
(5310 2460);
DISPLAY 0.680851 (5310 2460);
PAINT MONO (5310 2460);
FORCEPROP 0 LASTPIN (5300 2500) $PN 61
J 0
(5310 2510);
DISPLAY 0.680851 (5310 2510);
PAINT MONO (5310 2510);
FORCEPROP 0 LASTPIN (5300 2550) $PN 63
J 0
(5310 2560);
DISPLAY 0.680851 (5310 2560);
PAINT MONO (5310 2560);
FORCEPROP 0 LASTPIN (5300 2600) $PN 65
J 0
(5310 2610);
DISPLAY 0.680851 (5310 2610);
PAINT MONO (5310 2610);
FORCEPROP 0 LASTPIN (5300 2650) $PN 67
J 0
(5310 2660);
DISPLAY 0.680851 (5310 2660);
PAINT MONO (5310 2660);
FORCEPROP 0 LASTPIN (5300 2700) $PN 69
J 0
(5310 2710);
DISPLAY 0.680851 (5310 2710);
PAINT MONO (5310 2710);
FORCEPROP 0 LASTPIN (5300 2750) $PN 71
J 0
(5310 2760);
DISPLAY 0.680851 (5310 2760);
PAINT MONO (5310 2760);
FORCEPROP 0 LASTPIN (5300 2800) $PN 73
J 0
(5310 2810);
DISPLAY 0.680851 (5310 2810);
PAINT MONO (5310 2810);
FORCEPROP 0 LASTPIN (5300 2850) $PN 75
J 0
(5310 2860);
DISPLAY 0.680851 (5310 2860);
PAINT MONO (5310 2860);
FORCEPROP 0 LASTPIN (5300 2900) $PN 77
J 0
(5310 2910);
DISPLAY 0.680851 (5310 2910);
PAINT MONO (5310 2910);
FORCEPROP 0 LASTPIN (5300 2950) $PN 79
J 0
(5310 2960);
DISPLAY 0.680851 (5310 2960);
PAINT MONO (5310 2960);
FORCEPROP 0 LASTPIN (5300 3000) $PN 81
J 0
(5310 3010);
DISPLAY 0.680851 (5310 3010);
PAINT MONO (5310 3010);
FORCEPROP 0 LASTPIN (5300 3050) $PN 83
J 0
(5310 3060);
DISPLAY 0.680851 (5310 3060);
PAINT MONO (5310 3060);
FORCEPROP 0 LASTPIN (5300 3100) $PN 85
J 0
(5310 3110);
DISPLAY 0.680851 (5310 3110);
PAINT MONO (5310 3110);
FORCEPROP 0 LASTPIN (5300 3150) $PN 88
J 0
(5310 3160);
DISPLAY 0.680851 (5310 3160);
PAINT MONO (5310 3160);
FORCEPROP 0 LASTPIN (5300 3200) $PN 90
J 0
(5310 3210);
DISPLAY 0.680851 (5310 3210);
PAINT MONO (5310 3210);
FORCEPROP 0 LASTPIN (5300 3250) $PN 92
J 0
(5310 3260);
DISPLAY 0.680851 (5310 3260);
PAINT MONO (5310 3260);
FORCEPROP 0 LASTPIN (5300 3300) $PN 95
J 0
(5310 3310);
DISPLAY 0.680851 (5310 3310);
PAINT MONO (5310 3310);
FORCEPROP 0 LASTPIN (5300 3350) $PN 97
J 0
(5310 3360);
DISPLAY 0.680851 (5310 3360);
PAINT MONO (5310 3360);
FORCEPROP 0 LASTPIN (5300 3400) $PN 99
J 0
(5310 3410);
DISPLAY 0.680851 (5310 3410);
PAINT MONO (5310 3410);
FORCEPROP 0 LASTPIN (5300 3450) $PN 101
J 0
(5310 3460);
DISPLAY 0.680851 (5310 3460);
PAINT MONO (5310 3460);
FORCEPROP 0 LASTPIN (5300 3500) $PN 103
J 0
(5310 3510);
DISPLAY 0.680851 (5310 3510);
PAINT MONO (5310 3510);
FORCEPROP 0 LASTPIN (5300 3550) $PN 106
J 0
(5310 3560);
DISPLAY 0.680851 (5310 3560);
PAINT MONO (5310 3560);
FORCEPROP 0 LASTPIN (5300 3600) $PN 108
J 0
(5310 3610);
DISPLAY 0.680851 (5310 3610);
PAINT MONO (5310 3610);
FORCEPROP 0 LASTPIN (5300 3650) $PN 110
J 0
(5310 3660);
DISPLAY 0.680851 (5310 3660);
PAINT MONO (5310 3660);
FORCEPROP 0 LASTPIN (5300 3700) $PN 112
J 0
(5310 3710);
DISPLAY 0.680851 (5310 3710);
PAINT MONO (5310 3710);
FORCEPROP 0 LASTPIN (5300 3750) $PN 114
J 0
(5310 3760);
DISPLAY 0.680851 (5310 3760);
PAINT MONO (5310 3760);
FORCEPROP 0 LASTPIN (5300 3800) $PN 117
J 0
(5310 3810);
DISPLAY 0.680851 (5310 3810);
PAINT MONO (5310 3810);
FORCEPROP 0 LASTPIN (5300 3850) $PN 119
J 0
(5310 3860);
DISPLAY 0.680851 (5310 3860);
PAINT MONO (5310 3860);
FORCEPROP 0 LASTPIN (5300 3900) $PN 121
J 0
(5310 3910);
DISPLAY 0.680851 (5310 3910);
PAINT MONO (5310 3910);
FORCEPROP 0 LASTPIN (5300 3950) $PN 123
J 0
(5310 3960);
DISPLAY 0.680851 (5310 3960);
PAINT MONO (5310 3960);
FORCEPROP 0 LASTPIN (5300 4000) $PN 125
J 0
(5310 4010);
DISPLAY 0.680851 (5310 4010);
PAINT MONO (5310 4010);
FORCEPROP 0 LASTPIN (5300 4050) $PN 128
J 0
(5310 4060);
DISPLAY 0.680851 (5310 4060);
PAINT MONO (5310 4060);
FORCEPROP 0 LASTPIN (5300 4100) $PN 130
J 0
(5310 4110);
DISPLAY 0.680851 (5310 4110);
PAINT MONO (5310 4110);
FORCEPROP 0 LASTPIN (5300 4150) $PN 132
J 0
(5310 4160);
DISPLAY 0.680851 (5310 4160);
PAINT MONO (5310 4160);
FORCEPROP 0 LASTPIN (5300 4200) $PN 134
J 0
(5310 4210);
DISPLAY 0.680851 (5310 4210);
PAINT MONO (5310 4210);
FORCEPROP 0 LASTPIN (5300 4250) $PN 136
J 0
(5310 4260);
DISPLAY 0.680851 (5310 4260);
PAINT MONO (5310 4260);
FORCEPROP 0 LASTPIN (5300 4300) $PN 139
J 0
(5310 4310);
DISPLAY 0.680851 (5310 4310);
PAINT MONO (5310 4310);
FORCEPROP 0 LASTPIN (5300 4350) $PN 141
J 0
(5310 4360);
DISPLAY 0.680851 (5310 4360);
PAINT MONO (5310 4360);
FORCEPROP 0 LASTPIN (5300 4400) $PN 143
J 0
(5310 4410);
DISPLAY 0.680851 (5310 4410);
PAINT MONO (5310 4410);
FORCEPROP 0 LASTPIN (4100 1150) $PN 151
J 2
(4090 1160);
DISPLAY 0.680851 (4090 1160);
PAINT MONO (4090 1160);
FORCEPROP 0 LASTPIN (4100 1200) $PN 153
J 2
(4090 1210);
DISPLAY 0.680851 (4090 1210);
PAINT MONO (4090 1210);
FORCEPROP 0 LASTPIN (4100 1250) $PN 155
J 2
(4090 1260);
DISPLAY 0.680851 (4090 1260);
PAINT MONO (4090 1260);
FORCEPROP 0 LASTPIN (4100 1300) $PN 158
J 2
(4090 1310);
DISPLAY 0.680851 (4090 1310);
PAINT MONO (4090 1310);
FORCEPROP 0 LASTPIN (4100 1350) $PN 160
J 2
(4090 1360);
DISPLAY 0.680851 (4090 1360);
PAINT MONO (4090 1360);
FORCEPROP 0 LASTPIN (4100 1400) $PN 162
J 2
(4090 1410);
DISPLAY 0.680851 (4090 1410);
PAINT MONO (4090 1410);
FORCEPROP 0 LASTPIN (4100 1450) $PN 164
J 2
(4090 1460);
DISPLAY 0.680851 (4090 1460);
PAINT MONO (4090 1460);
FORCEPROP 0 LASTPIN (4100 1500) $PN 166
J 2
(4090 1510);
DISPLAY 0.680851 (4090 1510);
PAINT MONO (4090 1510);
FORCEPROP 0 LASTPIN (4100 1550) $PN 169
J 2
(4090 1560);
DISPLAY 0.680851 (4090 1560);
PAINT MONO (4090 1560);
FORCEPROP 0 LASTPIN (4100 1600) $PN 171
J 2
(4090 1610);
DISPLAY 0.680851 (4090 1610);
PAINT MONO (4090 1610);
FORCEPROP 0 LASTPIN (4100 1650) $PN 173
J 2
(4090 1660);
DISPLAY 0.680851 (4090 1660);
PAINT MONO (4090 1660);
FORCEPROP 0 LASTPIN (4100 1700) $PN 175
J 2
(4090 1710);
DISPLAY 0.680851 (4090 1710);
PAINT MONO (4090 1710);
FORCEPROP 0 LASTPIN (4100 1750) $PN 177
J 2
(4090 1760);
DISPLAY 0.680851 (4090 1760);
PAINT MONO (4090 1760);
FORCEPROP 0 LASTPIN (4100 1800) $PN 180
J 2
(4090 1810);
DISPLAY 0.680851 (4090 1810);
PAINT MONO (4090 1810);
FORCEPROP 0 LASTPIN (4100 1850) $PN 182
J 2
(4090 1860);
DISPLAY 0.680851 (4090 1860);
PAINT MONO (4090 1860);
FORCEPROP 0 LASTPIN (4100 1900) $PN 184
J 2
(4090 1910);
DISPLAY 0.680851 (4090 1910);
PAINT MONO (4090 1910);
FORCEPROP 0 LASTPIN (4100 1950) $PN 186
J 2
(4090 1960);
DISPLAY 0.680851 (4090 1960);
PAINT MONO (4090 1960);
FORCEPROP 0 LASTPIN (4100 2000) $PN 188
J 2
(4090 2010);
DISPLAY 0.680851 (4090 2010);
PAINT MONO (4090 2010);
FORCEPROP 0 LASTPIN (4100 2050) $PN 191
J 2
(4090 2060);
DISPLAY 0.680851 (4090 2060);
PAINT MONO (4090 2060);
FORCEPROP 0 LASTPIN (4100 2100) $PN 193
J 2
(4090 2110);
DISPLAY 0.680851 (4090 2110);
PAINT MONO (4090 2110);
FORCEPROP 0 LASTPIN (4100 2150) $PN 195
J 2
(4090 2160);
DISPLAY 0.680851 (4090 2160);
PAINT MONO (4090 2160);
FORCEPROP 0 LASTPIN (4100 2200) $PN 197
J 2
(4090 2210);
DISPLAY 0.680851 (4090 2210);
PAINT MONO (4090 2210);
FORCEPROP 0 LASTPIN (4100 2250) $PN 199
J 2
(4090 2260);
DISPLAY 0.680851 (4090 2260);
PAINT MONO (4090 2260);
FORCEPROP 0 LASTPIN (4100 2300) $PN 202
J 2
(4090 2310);
DISPLAY 0.680851 (4090 2310);
PAINT MONO (4090 2310);
FORCEPROP 0 LASTPIN (4100 2350) $PN 204
J 2
(4090 2360);
DISPLAY 0.680851 (4090 2360);
PAINT MONO (4090 2360);
FORCEPROP 0 LASTPIN (4100 2400) $PN 206
J 2
(4090 2410);
DISPLAY 0.680851 (4090 2410);
PAINT MONO (4090 2410);
FORCEPROP 0 LASTPIN (4100 2450) $PN 208
J 2
(4090 2460);
DISPLAY 0.680851 (4090 2460);
PAINT MONO (4090 2460);
FORCEPROP 0 LASTPIN (4100 2500) $PN 210
J 2
(4090 2510);
DISPLAY 0.680851 (4090 2510);
PAINT MONO (4090 2510);
FORCEPROP 0 LASTPIN (4100 2550) $PN 212
J 2
(4090 2560);
DISPLAY 0.680851 (4090 2560);
PAINT MONO (4090 2560);
FORCEPROP 0 LASTPIN (4100 2600) $PN 214
J 2
(4090 2610);
DISPLAY 0.680851 (4090 2610);
PAINT MONO (4090 2610);
FORCEPROP 0 LASTPIN (4100 2650) $PN 216
J 2
(4090 2660);
DISPLAY 0.680851 (4090 2660);
PAINT MONO (4090 2660);
FORCEPROP 0 LASTPIN (4100 2700) $PN 219
J 2
(4090 2710);
DISPLAY 0.680851 (4090 2710);
PAINT MONO (4090 2710);
FORCEPROP 0 LASTPIN (4100 2750) $PN 222
J 2
(4090 2760);
DISPLAY 0.680851 (4090 2760);
PAINT MONO (4090 2760);
FORCEPROP 0 LASTPIN (4100 2800) $PN 224
J 2
(4090 2810);
DISPLAY 0.680851 (4090 2810);
PAINT MONO (4090 2810);
FORCEPROP 0 LASTPIN (4100 2850) $PN 226
J 2
(4090 2860);
DISPLAY 0.680851 (4090 2860);
PAINT MONO (4090 2860);
FORCEPROP 0 LASTPIN (4100 2900) $PN 228
J 2
(4090 2910);
DISPLAY 0.680851 (4090 2910);
PAINT MONO (4090 2910);
FORCEPROP 0 LASTPIN (4100 2950) $PN 230
J 2
(4090 2960);
DISPLAY 0.680851 (4090 2960);
PAINT MONO (4090 2960);
FORCEPROP 0 LASTPIN (4100 3000) $PN 233
J 2
(4090 3010);
DISPLAY 0.680851 (4090 3010);
PAINT MONO (4090 3010);
FORCEPROP 0 LASTPIN (4100 3050) $PN 235
J 2
(4090 3060);
DISPLAY 0.680851 (4090 3060);
PAINT MONO (4090 3060);
FORCEPROP 0 LASTPIN (4100 3100) $PN 237
J 2
(4090 3110);
DISPLAY 0.680851 (4090 3110);
PAINT MONO (4090 3110);
FORCEPROP 0 LASTPIN (4100 3150) $PN 240
J 2
(4090 3160);
DISPLAY 0.680851 (4090 3160);
PAINT MONO (4090 3160);
FORCEPROP 0 LASTPIN (4100 3200) $PN 242
J 2
(4090 3210);
DISPLAY 0.680851 (4090 3210);
PAINT MONO (4090 3210);
FORCEPROP 0 LASTPIN (4100 3250) $PN 244
J 2
(4090 3260);
DISPLAY 0.680851 (4090 3260);
PAINT MONO (4090 3260);
FORCEPROP 0 LASTPIN (4100 3300) $PN 246
J 2
(4090 3310);
DISPLAY 0.680851 (4090 3310);
PAINT MONO (4090 3310);
FORCEPROP 0 LASTPIN (4100 3350) $PN 248
J 2
(4090 3360);
DISPLAY 0.680851 (4090 3360);
PAINT MONO (4090 3360);
FORCEPROP 0 LASTPIN (4100 3400) $PN 251
J 2
(4090 3410);
DISPLAY 0.680851 (4090 3410);
PAINT MONO (4090 3410);
FORCEPROP 0 LASTPIN (4100 3450) $PN 253
J 2
(4090 3460);
DISPLAY 0.680851 (4090 3460);
PAINT MONO (4090 3460);
FORCEPROP 0 LASTPIN (4100 3500) $PN 255
J 2
(4090 3510);
DISPLAY 0.680851 (4090 3510);
PAINT MONO (4090 3510);
FORCEPROP 0 LASTPIN (4100 3550) $PN 257
J 2
(4090 3560);
DISPLAY 0.680851 (4090 3560);
PAINT MONO (4090 3560);
FORCEPROP 0 LASTPIN (4100 3600) $PN 259
J 2
(4090 3610);
DISPLAY 0.680851 (4090 3610);
PAINT MONO (4090 3610);
FORCEPROP 0 LASTPIN (4100 3650) $PN 262
J 2
(4090 3660);
DISPLAY 0.680851 (4090 3660);
PAINT MONO (4090 3660);
FORCEPROP 0 LASTPIN (4100 3700) $PN 264
J 2
(4090 3710);
DISPLAY 0.680851 (4090 3710);
PAINT MONO (4090 3710);
FORCEPROP 0 LASTPIN (4100 3750) $PN 266
J 2
(4090 3760);
DISPLAY 0.680851 (4090 3760);
PAINT MONO (4090 3760);
FORCEPROP 0 LASTPIN (4100 3800) $PN 268
J 2
(4090 3810);
DISPLAY 0.680851 (4090 3810);
PAINT MONO (4090 3810);
FORCEPROP 0 LASTPIN (4100 3850) $PN 270
J 2
(4090 3860);
DISPLAY 0.680851 (4090 3860);
PAINT MONO (4090 3860);
FORCEPROP 0 LASTPIN (4100 3900) $PN 273
J 2
(4090 3910);
DISPLAY 0.680851 (4090 3910);
PAINT MONO (4090 3910);
FORCEPROP 0 LASTPIN (4100 3950) $PN 275
J 2
(4090 3960);
DISPLAY 0.680851 (4090 3960);
PAINT MONO (4090 3960);
FORCEPROP 0 LASTPIN (4100 4000) $PN 277
J 2
(4090 4010);
DISPLAY 0.680851 (4090 4010);
PAINT MONO (4090 4010);
FORCEPROP 0 LASTPIN (4100 4050) $PN 279
J 2
(4090 4060);
DISPLAY 0.680851 (4090 4060);
PAINT MONO (4090 4060);
FORCEPROP 0 LASTPIN (4100 4100) $PN 281
J 2
(4090 4110);
DISPLAY 0.680851 (4090 4110);
PAINT MONO (4090 4110);
FORCEPROP 0 LASTPIN (4100 4150) $PN 284
J 2
(4090 4160);
DISPLAY 0.680851 (4090 4160);
PAINT MONO (4090 4160);
FORCEPROP 0 LASTPIN (4100 4200) $PN 286
J 2
(4090 4210);
DISPLAY 0.680851 (4090 4210);
PAINT MONO (4090 4210);
FORCEPROP 0 LASTPIN (4100 4250) $PN 288
J 2
(4090 4260);
DISPLAY 0.680851 (4090 4260);
PAINT MONO (4090 4260);
FORCEPROP 1 LAST NEEDS_NO_SIZE TRUE
J 0
(4700 2775);
DISPLAY 0.723404 (4700 2775);
PAINT GREEN (4700 2775);
DISPLAY INVISIBLE (4700 2775);
FORCEPROP 1 LAST CDS_LMAN_SYM_OUTLINE -450,1775,450,-1775
J 0
(4700 2775);
DISPLAY 0.468085 (4700 2775);
PAINT GREEN (4700 2775);
DISPLAY INVISIBLE (4700 2775);
FORCEPROP 2 LAST CDS_LIB pure_quanta
J 0
(4700 2775);
DISPLAY INVISIBLE (4700 2775);
FORCEPROP 1 LAST PATH I175
J 0
(4700 2775);
DISPLAY 0.723404 (4700 2775);
PAINT GREEN (4700 2775);
DISPLAY INVISIBLE (4700 2775);
FORCEPROP 2 LAST CDS_LOCATION J19
J 0
(4250 4900);
DISPLAY 1.021277 (4250 4900);
DISPLAY INVISIBLE (4250 4900);
FORCEPROP 0 LAST $SEC 3
J 0
(4250 4900);
DISPLAY 0.680851 (4250 4900);
PAINT MONO (4250 4900);
DISPLAY INVISIBLE (4250 4900);
FORCEPROP 2 LAST CDS_SEC 3
J 0
(4250 4900);
DISPLAY 1.021277 (4250 4900);
DISPLAY INVISIBLE (4250 4900);
FORCEADD UNIVERSAL_GND..1
(5550 700);
FORCEPROP 3 LASTPIN (5550 750) SIG_NAME GND\g
J 0
(5560 760);
DISPLAY 0.659574 (5560 760);
PAINT MONO (5560 760);
DISPLAY INVISIBLE (5560 760);
FORCEPROP 1 LAST PATH I176
J 0
(5625 700);
DISPLAY 0.872340 (5625 700);
PAINT AQUA (5625 700);
DISPLAY INVISIBLE (5625 700);
FORCEPROP 1 LAST HDL_POWER GND
J 1
(5575 625);
DISPLAY 0.872340 (5575 625);
PAINT GREEN (5575 625);
DISPLAY INVISIBLE (5575 625);
FORCEPROP 2 LAST CDS_LIB logical_power
J 0
(5550 700);
PAINT MONO (5550 700);
DISPLAY INVISIBLE (5550 700);
FORCEADD VCC_CORE..1
(3850 4950);
FORCEPROP 3 LASTPIN (3850 4900) SIG_NAME P12V_S3_AUX_CPU1_NVDIMM\g
J 0
(3860 4910);
DISPLAY 0.659574 (3860 4910);
PAINT MONO (3860 4910);
DISPLAY INVISIBLE (3860 4910);
FORCEPROP 1 LAST HDL_POWER P12V_S3_AUX_CPU1_NVDIMM
J 1
(3850 5000);
DISPLAY 1.148936 (3850 5000);
PAINT GREEN (3850 5000);
FORCEPROP 2 LAST CDS_LIB logical_power
J 0
(3850 4950);
PAINT MONO (3850 4950);
DISPLAY INVISIBLE (3850 4950);
FORCEPROP 1 LAST PATH I177
J 0
(3900 4975);
DISPLAY 0.872340 (3900 4975);
PAINT AQUA (3900 4975);
DISPLAY INVISIBLE (3900 4975);
FORCEADD SCONN288_ADR50017P130CC..2
(1275 3400);
FORCEPROP 1 LAST PART_NUMBER DFHST8FS461
J 0
(682 4700);
DISPLAY 0.723404 (682 4700);
PAINT GREEN (682 4700);
DISPLAY INVISIBLE (682 4700);
FORCEPROP 1 LAST MATERIAL IO
J 0
(682 4573);
DISPLAY 0.723404 (682 4573);
PAINT GREEN (682 4573);
FORCEPROP 2 LAST PART_TYPE SMLF
J 0
(693 4853);
DISPLAY 1.021277 (693 4853);
FORCEPROP 2 LAST VALUE SCONN288_ADR50017-P130CC
J 0
(693 4803);
DISPLAY 1.021277 (693 4803);
FORCEPROP 1 LAST LOCATION J19
J 0
(675 4750);
DISPLAY 0.723404 (675 4750);
PAINT GREEN (675 4750);
FORCEPROP 0 LASTPIN (2025 3450) $PN 12
J 0
(2035 3460);
DISPLAY 0.680851 (2035 3460);
PAINT MONO (2035 3460);
FORCEPROP 0 LASTPIN (2025 3500) $PN 11
J 0
(2035 3510);
DISPLAY 0.680851 (2035 3510);
PAINT MONO (2035 3510);
FORCEPROP 0 LASTPIN (2025 2400) $PN 105
J 0
(2035 2410);
DISPLAY 0.680851 (2035 2410);
PAINT MONO (2035 2410);
FORCEPROP 0 LASTPIN (2025 2450) $PN 104
J 0
(2035 2460);
DISPLAY 0.680851 (2035 2460);
PAINT MONO (2035 2460);
FORCEPROP 0 LASTPIN (2025 3550) $PN 23
J 0
(2035 3560);
DISPLAY 0.680851 (2035 3560);
PAINT MONO (2035 3560);
FORCEPROP 0 LASTPIN (2025 3600) $PN 22
J 0
(2035 3610);
DISPLAY 0.680851 (2035 3610);
PAINT MONO (2035 3610);
FORCEPROP 0 LASTPIN (2025 2500) $PN 116
J 0
(2035 2510);
DISPLAY 0.680851 (2035 2510);
PAINT MONO (2035 2510);
FORCEPROP 0 LASTPIN (2025 2550) $PN 115
J 0
(2035 2560);
DISPLAY 0.680851 (2035 2560);
PAINT MONO (2035 2560);
FORCEPROP 0 LASTPIN (2025 3650) $PN 34
J 0
(2035 3660);
DISPLAY 0.680851 (2035 3660);
PAINT MONO (2035 3660);
FORCEPROP 0 LASTPIN (2025 3700) $PN 33
J 0
(2035 3710);
DISPLAY 0.680851 (2035 3710);
PAINT MONO (2035 3710);
FORCEPROP 0 LASTPIN (2025 2600) $PN 127
J 0
(2035 2610);
DISPLAY 0.680851 (2035 2610);
PAINT MONO (2035 2610);
FORCEPROP 0 LASTPIN (2025 2650) $PN 126
J 0
(2035 2660);
DISPLAY 0.680851 (2035 2660);
PAINT MONO (2035 2660);
FORCEPROP 0 LASTPIN (2025 3750) $PN 45
J 0
(2035 3760);
DISPLAY 0.680851 (2035 3760);
PAINT MONO (2035 3760);
FORCEPROP 0 LASTPIN (2025 3800) $PN 44
J 0
(2035 3810);
DISPLAY 0.680851 (2035 3810);
PAINT MONO (2035 3810);
FORCEPROP 0 LASTPIN (2025 2700) $PN 138
J 0
(2035 2710);
DISPLAY 0.680851 (2035 2710);
PAINT MONO (2035 2710);
FORCEPROP 0 LASTPIN (2025 2750) $PN 137
J 0
(2035 2760);
DISPLAY 0.680851 (2035 2760);
PAINT MONO (2035 2760);
FORCEPROP 0 LASTPIN (2025 3850) $PN 56
J 0
(2035 3860);
DISPLAY 0.680851 (2035 3860);
PAINT MONO (2035 3860);
FORCEPROP 0 LASTPIN (2025 3900) $PN 55
J 0
(2035 3910);
DISPLAY 0.680851 (2035 3910);
PAINT MONO (2035 3910);
FORCEPROP 0 LASTPIN (2025 2800) $PN 238
J 0
(2035 2810);
DISPLAY 0.680851 (2035 2810);
PAINT MONO (2035 2810);
FORCEPROP 0 LASTPIN (2025 2850) $PN 239
J 0
(2035 2860);
DISPLAY 0.680851 (2035 2860);
PAINT MONO (2035 2860);
FORCEPROP 0 LASTPIN (2025 3950) $PN 156
J 0
(2035 3960);
DISPLAY 0.680851 (2035 3960);
PAINT MONO (2035 3960);
FORCEPROP 0 LASTPIN (2025 4000) $PN 157
J 0
(2035 4010);
DISPLAY 0.680851 (2035 4010);
PAINT MONO (2035 4010);
FORCEPROP 0 LASTPIN (2025 2900) $PN 249
J 0
(2035 2910);
DISPLAY 0.680851 (2035 2910);
PAINT MONO (2035 2910);
FORCEPROP 0 LASTPIN (2025 2950) $PN 250
J 0
(2035 2960);
DISPLAY 0.680851 (2035 2960);
PAINT MONO (2035 2960);
FORCEPROP 0 LASTPIN (2025 4050) $PN 167
J 0
(2035 4060);
DISPLAY 0.680851 (2035 4060);
PAINT MONO (2035 4060);
FORCEPROP 0 LASTPIN (2025 4100) $PN 168
J 0
(2035 4110);
DISPLAY 0.680851 (2035 4110);
PAINT MONO (2035 4110);
FORCEPROP 0 LASTPIN (2025 3000) $PN 260
J 0
(2035 3010);
DISPLAY 0.680851 (2035 3010);
PAINT MONO (2035 3010);
FORCEPROP 0 LASTPIN (2025 3050) $PN 261
J 0
(2035 3060);
DISPLAY 0.680851 (2035 3060);
PAINT MONO (2035 3060);
FORCEPROP 0 LASTPIN (2025 4150) $PN 178
J 0
(2035 4160);
DISPLAY 0.680851 (2035 4160);
PAINT MONO (2035 4160);
FORCEPROP 0 LASTPIN (2025 4200) $PN 179
J 0
(2035 4210);
DISPLAY 0.680851 (2035 4210);
PAINT MONO (2035 4210);
FORCEPROP 0 LASTPIN (2025 3100) $PN 271
J 0
(2035 3110);
DISPLAY 0.680851 (2035 3110);
PAINT MONO (2035 3110);
FORCEPROP 0 LASTPIN (2025 3150) $PN 272
J 0
(2035 3160);
DISPLAY 0.680851 (2035 3160);
PAINT MONO (2035 3160);
FORCEPROP 0 LASTPIN (2025 4250) $PN 189
J 0
(2035 4260);
DISPLAY 0.680851 (2035 4260);
PAINT MONO (2035 4260);
FORCEPROP 0 LASTPIN (2025 4300) $PN 190
J 0
(2035 4310);
DISPLAY 0.680851 (2035 4310);
PAINT MONO (2035 4310);
FORCEPROP 0 LASTPIN (2025 3200) $PN 282
J 0
(2035 3210);
DISPLAY 0.680851 (2035 3210);
PAINT MONO (2035 3210);
FORCEPROP 0 LASTPIN (2025 3250) $PN 283
J 0
(2035 3260);
DISPLAY 0.680851 (2035 3260);
PAINT MONO (2035 3260);
FORCEPROP 0 LASTPIN (2025 4350) $PN 200
J 0
(2035 4360);
DISPLAY 0.680851 (2035 4360);
PAINT MONO (2035 4360);
FORCEPROP 0 LASTPIN (2025 4400) $PN 201
J 0
(2035 4410);
DISPLAY 0.680851 (2035 4410);
PAINT MONO (2035 4410);
FORCEPROP 0 LASTPIN (2025 3300) $PN 94
J 0
(2035 3310);
DISPLAY 0.680851 (2035 3310);
PAINT MONO (2035 3310);
FORCEPROP 0 LASTPIN (2025 3350) $PN 93
J 0
(2035 3360);
DISPLAY 0.680851 (2035 3360);
PAINT MONO (2035 3360);
FORCEPROP 1 LAST NEEDS_NO_SIZE TRUE
J 0
(1275 3400);
DISPLAY 0.723404 (1275 3400);
PAINT GREEN (1275 3400);
DISPLAY INVISIBLE (1275 3400);
FORCEPROP 1 LAST CDS_LMAN_SYM_OUTLINE -600,1150,600,-1150
J 0
(1275 3400);
DISPLAY 0.468085 (1275 3400);
PAINT GREEN (1275 3400);
DISPLAY INVISIBLE (1275 3400);
FORCEPROP 2 LAST CDS_LIB pure_quanta
J 0
(1275 3400);
DISPLAY INVISIBLE (1275 3400);
FORCEPROP 1 LAST PATH I178
J 0
(1275 3400);
DISPLAY 0.723404 (1275 3400);
PAINT GREEN (1275 3400);
DISPLAY INVISIBLE (1275 3400);
FORCEPROP 0 LAST $SEC 2
J 0
(700 4925);
DISPLAY 0.680851 (700 4925);
PAINT MONO (700 4925);
DISPLAY INVISIBLE (700 4925);
FORCEPROP 0 LAST CDS_SEC 2
J 0
(700 4925);
DISPLAY 1.021277 (700 4925);
DISPLAY INVISIBLE (700 4925);
FORCEADD OFFPAGE..1
(-1950 1625);
FORCEPROP 2 LAST $XR7 105 
J 0
(-3012 1625);
DISPLAY 0.638298 (-3012 1625);
PAINT MONO (-3012 1625);
FORCEPROP 2 LAST $XR6 104 
J 0
(-2892 1625);
DISPLAY 0.638298 (-2892 1625);
PAINT MONO (-2892 1625);
FORCEPROP 2 LAST $XR5 103 
J 0
(-2772 1625);
DISPLAY 0.638298 (-2772 1625);
PAINT MONO (-2772 1625);
FORCEPROP 2 LAST $XR4 102 
J 0
(-2652 1625);
DISPLAY 0.638298 (-2652 1625);
PAINT MONO (-2652 1625);
FORCEPROP 2 LAST $XR3 101 
J 0
(-2532 1625);
DISPLAY 0.638298 (-2532 1625);
PAINT MONO (-2532 1625);
FORCEPROP 2 LAST $XR2 99 
J 0
(-2412 1625);
DISPLAY 0.638298 (-2412 1625);
PAINT MONO (-2412 1625);
FORCEPROP 2 LAST $XR1 98 
J 0
(-2322 1625);
DISPLAY 0.638298 (-2322 1625);
PAINT MONO (-2322 1625);
FORCEPROP 2 LAST $XR0 230 
J 0
(-2232 1625);
DISPLAY 0.638298 (-2232 1625);
PAINT MONO (-2232 1625);
FORCEPROP 2 LAST CDS_LIB standard
J 2
(-1950 1625);
DISPLAY INVISIBLE (-1950 1625);
FORCEPROP 1 LAST OFFPAGE TRUE
J 0
(-1625 1500);
DISPLAY 0.872340 (-1625 1500);
DISPLAY INVISIBLE (-1625 1500);
FORCEPROP 1 LAST COMMENT_BODY TRUE
J 0
(-1825 1525);
DISPLAY 0.872340 (-1825 1525);
PAINT GREEN (-1825 1525);
DISPLAY INVISIBLE (-1825 1525);
FORCEPROP 2 LAST PATH I179
J 2
(-2125 1700);
DISPLAY 1.021277 (-2125 1700);
DISPLAY INVISIBLE (-2125 1700);
FORCEADD OFFPAGE..1
(-3150 3300);
FORCEPROP 2 LAST $XR0 52 
J 0
(-3371 3300);
DISPLAY 0.638298 (-3371 3300);
PAINT MONO (-3371 3300);
FORCEPROP 2 LAST CDS_LIB standard
J 0
(-3150 3300);
PAINT MONO (-3150 3300);
DISPLAY INVISIBLE (-3150 3300);
FORCEPROP 1 LAST OFFPAGE TRUE
J 0
(-2825 3175);
DISPLAY 0.872340 (-2825 3175);
DISPLAY INVISIBLE (-2825 3175);
FORCEPROP 1 LAST COMMENT_BODY TRUE
J 0
(-3025 3200);
DISPLAY 0.872340 (-3025 3200);
PAINT GREEN (-3025 3200);
DISPLAY INVISIBLE (-3025 3200);
FORCEPROP 2 LAST PATH I18
J 0
(-3100 3375);
DISPLAY 1.021277 (-3100 3375);
DISPLAY INVISIBLE (-3100 3375);
FORCEADD Q_RES..1
(-3175 1675);
FORCEPROP 1 LAST PART_NUMBER CS04992FB07
J 0
(-3075 1650);
DISPLAY 0.404255 (-3075 1650);
DISPLAY INVISIBLE (-3075 1650);
FORCEPROP 1 LAST MATERIAL CHIP
J 0
(-3325 1650);
DISPLAY 0.404255 (-3325 1650);
FORCEPROP 1 LAST VALUE 49.9
J 2
(-2950 1675);
DISPLAY 0.510638 (-2950 1675);
FORCEPROP 1 LAST $LOCATION R3893
J 0
(-3450 1675);
DISPLAY 0.638298 (-3450 1675);
FORCEPROP 1 LASTPIN (-3275 1675) $PN 1
J 0
(-3263 1687);
DISPLAY 0.787234 (-3263 1687);
PAINT MONO (-3263 1687);
FORCEPROP 1 LASTPIN (-3075 1675) $PN 2
J 0
(-3113 1687);
DISPLAY 0.787234 (-3113 1687);
PAINT MONO (-3113 1687);
FORCEPROP 2 LAST CDS_LIB pure_quanta
J 0
(-3175 1675);
DISPLAY INVISIBLE (-3175 1675);
FORCEPROP 1 LAST PACK_TYPE 0402LF
J 0
(-2875 1675);
DISPLAY 0.510638 (-2875 1675);
DISPLAY INVISIBLE (-2875 1675);
FORCEPROP 1 LAST TOLERANCE 1%
J 0
(-2950 1675);
DISPLAY 0.510638 (-2950 1675);
DISPLAY INVISIBLE (-2950 1675);
FORCEPROP 1 LAST WATTAGE 1/16W
J 2
(-2875 1625);
DISPLAY 0.404255 (-2875 1625);
DISPLAY INVISIBLE (-2875 1625);
FORCEPROP 1 LAST PATH I180
J 0
(-3225 1825);
DISPLAY 0.978723 (-3225 1825);
PAINT WHITE (-3225 1825);
DISPLAY INVISIBLE (-3225 1825);
FORCEPROP 0 LAST CDS_LOCATION R3893
J 0
(-3325 1725);
DISPLAY 1.021277 (-3325 1725);
DISPLAY INVISIBLE (-3325 1725);
FORCEPROP 0 LAST $SEC 1
J 0
(-3325 1725);
DISPLAY 0.680851 (-3325 1725);
PAINT MONO (-3325 1725);
DISPLAY INVISIBLE (-3325 1725);
FORCEPROP 0 LAST CDS_SEC 1
J 0
(-3325 1725);
DISPLAY 1.021277 (-3325 1725);
DISPLAY INVISIBLE (-3325 1725);
FORCEADD OFFPAGE..1
(-3150 3400);
FORCEPROP 2 LAST $XR0 52 
J 0
(-3371 3400);
DISPLAY 0.638298 (-3371 3400);
PAINT MONO (-3371 3400);
FORCEPROP 2 LAST CDS_LIB standard
J 0
(-3150 3400);
PAINT MONO (-3150 3400);
DISPLAY INVISIBLE (-3150 3400);
FORCEPROP 1 LAST OFFPAGE TRUE
J 0
(-2825 3275);
DISPLAY 0.872340 (-2825 3275);
DISPLAY INVISIBLE (-2825 3275);
FORCEPROP 1 LAST COMMENT_BODY TRUE
J 0
(-3025 3300);
DISPLAY 0.872340 (-3025 3300);
PAINT GREEN (-3025 3300);
DISPLAY INVISIBLE (-3025 3300);
FORCEPROP 2 LAST PATH I19
J 0
(-3100 3475);
DISPLAY 1.021277 (-3100 3475);
DISPLAY INVISIBLE (-3100 3475);
FORCEADD UNIVERSAL_GND..1
(-2000 25);
FORCEPROP 3 LASTPIN (-2000 75) SIG_NAME GND\g
J 0
(-1990 85);
DISPLAY 0.659574 (-1990 85);
PAINT MONO (-1990 85);
DISPLAY INVISIBLE (-1990 85);
FORCEPROP 1 LAST PATH I2
J 0
(-1925 25);
DISPLAY 0.872340 (-1925 25);
PAINT AQUA (-1925 25);
DISPLAY INVISIBLE (-1925 25);
FORCEPROP 1 LAST HDL_POWER GND
J 1
(-1975 -50);
DISPLAY 0.872340 (-1975 -50);
PAINT GREEN (-1975 -50);
DISPLAY INVISIBLE (-1975 -50);
FORCEPROP 2 LAST CDS_LIB logical_power
J 0
(-2000 25);
PAINT MONO (-2000 25);
DISPLAY INVISIBLE (-2000 25);
FORCEADD OFFPAGE..1
(-3150 3450);
FORCEPROP 2 LAST $XR0 52 
J 0
(-3371 3450);
DISPLAY 0.638298 (-3371 3450);
PAINT MONO (-3371 3450);
FORCEPROP 2 LAST CDS_LIB standard
J 0
(-3150 3450);
PAINT MONO (-3150 3450);
DISPLAY INVISIBLE (-3150 3450);
FORCEPROP 1 LAST OFFPAGE TRUE
J 0
(-2825 3325);
DISPLAY 0.872340 (-2825 3325);
DISPLAY INVISIBLE (-2825 3325);
FORCEPROP 1 LAST COMMENT_BODY TRUE
J 0
(-3025 3350);
DISPLAY 0.872340 (-3025 3350);
PAINT GREEN (-3025 3350);
DISPLAY INVISIBLE (-3025 3350);
FORCEPROP 2 LAST PATH I20
J 0
(-3100 3525);
DISPLAY 1.021277 (-3100 3525);
DISPLAY INVISIBLE (-3100 3525);
FORCEADD OFFPAGE..1
(-3150 3550);
FORCEPROP 2 LAST $XR1 101 
J 0
(-3491 3550);
DISPLAY 0.638298 (-3491 3550);
PAINT MONO (-3491 3550);
FORCEPROP 2 LAST $XR0 52 
J 0
(-3371 3550);
DISPLAY 0.638298 (-3371 3550);
PAINT MONO (-3371 3550);
FORCEPROP 2 LAST CDS_LIB standard
J 0
(-3150 3550);
PAINT MONO (-3150 3550);
DISPLAY INVISIBLE (-3150 3550);
FORCEPROP 1 LAST OFFPAGE TRUE
J 0
(-2825 3425);
DISPLAY 0.872340 (-2825 3425);
DISPLAY INVISIBLE (-2825 3425);
FORCEPROP 1 LAST COMMENT_BODY TRUE
J 0
(-3025 3450);
DISPLAY 0.872340 (-3025 3450);
PAINT GREEN (-3025 3450);
DISPLAY INVISIBLE (-3025 3450);
FORCEPROP 2 LAST PATH I21
J 0
(-3100 3625);
DISPLAY 1.021277 (-3100 3625);
DISPLAY INVISIBLE (-3100 3625);
FORCEADD OFFPAGE..1
(-3150 3600);
FORCEPROP 2 LAST $XR1 101 
J 0
(-3491 3600);
DISPLAY 0.638298 (-3491 3600);
PAINT MONO (-3491 3600);
FORCEPROP 2 LAST $XR0 52 
J 0
(-3371 3600);
DISPLAY 0.638298 (-3371 3600);
PAINT MONO (-3371 3600);
FORCEPROP 2 LAST CDS_LIB standard
J 0
(-3150 3600);
PAINT MONO (-3150 3600);
DISPLAY INVISIBLE (-3150 3600);
FORCEPROP 1 LAST OFFPAGE TRUE
J 0
(-2825 3475);
DISPLAY 0.872340 (-2825 3475);
DISPLAY INVISIBLE (-2825 3475);
FORCEPROP 1 LAST COMMENT_BODY TRUE
J 0
(-3025 3500);
DISPLAY 0.872340 (-3025 3500);
PAINT GREEN (-3025 3500);
DISPLAY INVISIBLE (-3025 3500);
FORCEPROP 2 LAST PATH I22
J 0
(-3100 3675);
DISPLAY 1.021277 (-3100 3675);
DISPLAY INVISIBLE (-3100 3675);
FORCEADD OFFPAGE..1
(-3150 4025);
FORCEPROP 2 LAST $XR1 101 
J 0
(-3491 4025);
DISPLAY 0.638298 (-3491 4025);
PAINT MONO (-3491 4025);
FORCEPROP 2 LAST $XR0 52 
J 0
(-3371 4025);
DISPLAY 0.638298 (-3371 4025);
PAINT MONO (-3371 4025);
FORCEPROP 2 LAST CDS_LIB standard
J 0
(-3150 4025);
PAINT MONO (-3150 4025);
DISPLAY INVISIBLE (-3150 4025);
FORCEPROP 1 LAST OFFPAGE TRUE
J 0
(-2825 3900);
DISPLAY 0.872340 (-2825 3900);
DISPLAY INVISIBLE (-2825 3900);
FORCEPROP 1 LAST COMMENT_BODY TRUE
J 0
(-3025 3925);
DISPLAY 0.872340 (-3025 3925);
PAINT GREEN (-3025 3925);
DISPLAY INVISIBLE (-3025 3925);
FORCEPROP 2 LAST PATH I23
J 0
(-3100 4100);
DISPLAY 1.021277 (-3100 4100);
DISPLAY INVISIBLE (-3100 4100);
FORCEADD OFFPAGE..1
(-3150 4425);
FORCEPROP 2 LAST $XR1 101 
J 0
(-3491 4425);
DISPLAY 0.638298 (-3491 4425);
PAINT MONO (-3491 4425);
FORCEPROP 2 LAST $XR0 52 
J 0
(-3371 4425);
DISPLAY 0.638298 (-3371 4425);
PAINT MONO (-3371 4425);
FORCEPROP 2 LAST CDS_LIB standard
J 0
(-3150 4425);
PAINT MONO (-3150 4425);
DISPLAY INVISIBLE (-3150 4425);
FORCEPROP 1 LAST OFFPAGE TRUE
J 0
(-2825 4300);
DISPLAY 0.872340 (-2825 4300);
DISPLAY INVISIBLE (-2825 4300);
FORCEPROP 1 LAST COMMENT_BODY TRUE
J 0
(-3025 4325);
DISPLAY 0.872340 (-3025 4325);
PAINT GREEN (-3025 4325);
DISPLAY INVISIBLE (-3025 4325);
FORCEPROP 2 LAST PATH I24
J 0
(-3100 4500);
DISPLAY 1.021277 (-3100 4500);
DISPLAY INVISIBLE (-3100 4500);
FORCEADD SCONN288_ADR50017P130CC..1
(-1400 2675);
FORCEPROP 1 LAST PART_NUMBER DFHST8FS461
J 0
(-1845 4697);
DISPLAY 0.723404 (-1845 4697);
PAINT GREEN (-1845 4697);
DISPLAY INVISIBLE (-1845 4697);
FORCEPROP 1 LAST MATERIAL IO
J 0
(-1845 4570);
DISPLAY 0.723404 (-1845 4570);
PAINT GREEN (-1845 4570);
FORCEPROP 2 LAST VALUE SCONN288_ADR50017-P130CC
J 0
(-1850 4800);
DISPLAY 1.021277 (-1850 4800);
FORCEPROP 2 LAST PART_TYPE SMLF
J 0
(-1850 4850);
DISPLAY 1.021277 (-1850 4850);
FORCEPROP 1 LAST $LOCATION J19
J 0
(-1850 4750);
DISPLAY 0.723404 (-1850 4750);
PAINT GREEN (-1850 4750);
FORCEPROP 0 LASTPIN (-2000 2050) $PN 62
J 2
(-2010 2060);
DISPLAY 0.680851 (-2010 2060);
PAINT MONO (-2010 2060);
FORCEPROP 0 LASTPIN (-2000 4100) $PN 66
J 2
(-2010 4110);
DISPLAY 0.680851 (-2010 4110);
PAINT MONO (-2010 4110);
FORCEPROP 0 LASTPIN (-2000 3700) $PN 76
J 2
(-2010 3710);
DISPLAY 0.680851 (-2010 3710);
PAINT MONO (-2010 3710);
FORCEPROP 0 LASTPIN (-2000 4150) $PN 211
J 2
(-2010 4160);
DISPLAY 0.680851 (-2010 4160);
PAINT MONO (-2010 4160);
FORCEPROP 0 LASTPIN (-2000 3750) $PN 221
J 2
(-2010 3760);
DISPLAY 0.680851 (-2010 3760);
PAINT MONO (-2010 3760);
FORCEPROP 0 LASTPIN (-2000 4200) $PN 68
J 2
(-2010 4210);
DISPLAY 0.680851 (-2010 4210);
PAINT MONO (-2010 4210);
FORCEPROP 0 LASTPIN (-2000 3800) $PN 78
J 2
(-2010 3810);
DISPLAY 0.680851 (-2010 3810);
PAINT MONO (-2010 3810);
FORCEPROP 0 LASTPIN (-2000 4250) $PN 213
J 2
(-2010 4260);
DISPLAY 0.680851 (-2010 4260);
PAINT MONO (-2010 4260);
FORCEPROP 0 LASTPIN (-2000 3850) $PN 223
J 2
(-2010 3860);
DISPLAY 0.680851 (-2010 3860);
PAINT MONO (-2010 3860);
FORCEPROP 0 LASTPIN (-2000 4300) $PN 70
J 2
(-2010 4310);
DISPLAY 0.680851 (-2010 4310);
PAINT MONO (-2010 4310);
FORCEPROP 0 LASTPIN (-2000 3900) $PN 80
J 2
(-2010 3910);
DISPLAY 0.680851 (-2010 3910);
PAINT MONO (-2010 3910);
FORCEPROP 0 LASTPIN (-2000 4350) $PN 215
J 2
(-2010 4360);
DISPLAY 0.680851 (-2010 4360);
PAINT MONO (-2010 4360);
FORCEPROP 0 LASTPIN (-2000 3950) $PN 225
J 2
(-2010 3960);
DISPLAY 0.680851 (-2010 3960);
PAINT MONO (-2010 3960);
FORCEPROP 0 LASTPIN (-2000 4400) $PN 72
J 2
(-2010 4410);
DISPLAY 0.680851 (-2010 4410);
PAINT MONO (-2010 4410);
FORCEPROP 0 LASTPIN (-2000 4000) $PN 82
J 2
(-2010 4010);
DISPLAY 0.680851 (-2010 4010);
PAINT MONO (-2010 4010);
FORCEPROP 0 LASTPIN (-2000 2650) $PN 51
J 2
(-2010 2660);
DISPLAY 0.680851 (-2010 2660);
PAINT MONO (-2010 2660);
FORCEPROP 0 LASTPIN (-2000 2200) $PN 96
J 2
(-2010 2210);
DISPLAY 0.680851 (-2010 2210);
PAINT MONO (-2010 2210);
FORCEPROP 0 LASTPIN (-2000 2700) $PN 53
J 2
(-2010 2710);
DISPLAY 0.680851 (-2010 2710);
PAINT MONO (-2010 2710);
FORCEPROP 0 LASTPIN (-2000 2250) $PN 98
J 2
(-2010 2260);
DISPLAY 0.680851 (-2010 2260);
PAINT MONO (-2010 2260);
FORCEPROP 0 LASTPIN (-2000 2750) $PN 196
J 2
(-2010 2760);
DISPLAY 0.680851 (-2010 2760);
PAINT MONO (-2010 2760);
FORCEPROP 0 LASTPIN (-2000 2300) $PN 241
J 2
(-2010 2310);
DISPLAY 0.680851 (-2010 2310);
PAINT MONO (-2010 2310);
FORCEPROP 0 LASTPIN (-2000 2800) $PN 198
J 2
(-2010 2810);
DISPLAY 0.680851 (-2010 2810);
PAINT MONO (-2010 2810);
FORCEPROP 0 LASTPIN (-2000 2350) $PN 243
J 2
(-2010 2360);
DISPLAY 0.680851 (-2010 2360);
PAINT MONO (-2010 2360);
FORCEPROP 0 LASTPIN (-2000 2850) $PN 58
J 2
(-2010 2860);
DISPLAY 0.680851 (-2010 2860);
PAINT MONO (-2010 2860);
FORCEPROP 0 LASTPIN (-2000 2400) $PN 89
J 2
(-2010 2410);
DISPLAY 0.680851 (-2010 2410);
PAINT MONO (-2010 2410);
FORCEPROP 0 LASTPIN (-2000 2900) $PN 60
J 2
(-2010 2910);
DISPLAY 0.680851 (-2010 2910);
PAINT MONO (-2010 2910);
FORCEPROP 0 LASTPIN (-2000 2450) $PN 91
J 2
(-2010 2460);
DISPLAY 0.680851 (-2010 2460);
PAINT MONO (-2010 2460);
FORCEPROP 0 LASTPIN (-2000 2950) $PN 203
J 2
(-2010 2960);
DISPLAY 0.680851 (-2010 2960);
PAINT MONO (-2010 2960);
FORCEPROP 0 LASTPIN (-2000 2500) $PN 234
J 2
(-2010 2510);
DISPLAY 0.680851 (-2010 2510);
PAINT MONO (-2010 2510);
FORCEPROP 0 LASTPIN (-2000 3000) $PN 205
J 2
(-2010 3010);
DISPLAY 0.680851 (-2010 3010);
PAINT MONO (-2010 3010);
FORCEPROP 0 LASTPIN (-2000 2550) $PN 236
J 2
(-2010 2560);
DISPLAY 0.680851 (-2010 2560);
PAINT MONO (-2010 2560);
FORCEPROP 0 LASTPIN (-2000 3100) $PN 218
J 2
(-2010 3110);
DISPLAY 0.680851 (-2010 3110);
PAINT MONO (-2010 3110);
FORCEPROP 0 LASTPIN (-2000 3150) $PN 217
J 2
(-2010 3160);
DISPLAY 0.680851 (-2010 3160);
PAINT MONO (-2010 3160);
FORCEPROP 0 LASTPIN (-2000 3400) $PN 64
J 2
(-2010 3410);
DISPLAY 0.680851 (-2010 3410);
PAINT MONO (-2010 3410);
FORCEPROP 0 LASTPIN (-2000 3250) $PN 84
J 2
(-2010 3260);
DISPLAY 0.680851 (-2010 3260);
PAINT MONO (-2010 3260);
FORCEPROP 0 LASTPIN (-2000 3450) $PN 209
J 2
(-2010 3460);
DISPLAY 0.680851 (-2010 3460);
PAINT MONO (-2010 3460);
FORCEPROP 0 LASTPIN (-2000 3300) $PN 229
J 2
(-2010 3310);
DISPLAY 0.680851 (-2010 3310);
PAINT MONO (-2010 3310);
FORCEPROP 0 LASTPIN (-800 2850) $PN 7
J 0
(-790 2860);
DISPLAY 0.680851 (-790 2860);
PAINT MONO (-790 2860);
FORCEPROP 0 LASTPIN (-800 1200) $PN 100
J 0
(-790 1210);
DISPLAY 0.680851 (-790 1210);
PAINT MONO (-790 1210);
FORCEPROP 0 LASTPIN (-800 2900) $PN 9
J 0
(-790 2910);
DISPLAY 0.680851 (-790 2910);
PAINT MONO (-790 2910);
FORCEPROP 0 LASTPIN (-800 1250) $PN 102
J 0
(-790 1260);
DISPLAY 0.680851 (-790 1260);
PAINT MONO (-790 1260);
FORCEPROP 0 LASTPIN (-800 2950) $PN 152
J 0
(-790 2960);
DISPLAY 0.680851 (-790 2960);
PAINT MONO (-790 2960);
FORCEPROP 0 LASTPIN (-800 1300) $PN 245
J 0
(-790 1310);
DISPLAY 0.680851 (-790 1310);
PAINT MONO (-790 1310);
FORCEPROP 0 LASTPIN (-800 3000) $PN 154
J 0
(-790 3010);
DISPLAY 0.680851 (-790 3010);
PAINT MONO (-790 3010);
FORCEPROP 0 LASTPIN (-800 1350) $PN 247
J 0
(-790 1360);
DISPLAY 0.680851 (-790 1360);
PAINT MONO (-790 1360);
FORCEPROP 0 LASTPIN (-800 3050) $PN 14
J 0
(-790 3060);
DISPLAY 0.680851 (-790 3060);
PAINT MONO (-790 3060);
FORCEPROP 0 LASTPIN (-800 1400) $PN 107
J 0
(-790 1410);
DISPLAY 0.680851 (-790 1410);
PAINT MONO (-790 1410);
FORCEPROP 0 LASTPIN (-800 3100) $PN 16
J 0
(-790 3110);
DISPLAY 0.680851 (-790 3110);
PAINT MONO (-790 3110);
FORCEPROP 0 LASTPIN (-800 1450) $PN 109
J 0
(-790 1460);
DISPLAY 0.680851 (-790 1460);
PAINT MONO (-790 1460);
FORCEPROP 0 LASTPIN (-800 3150) $PN 159
J 0
(-790 3160);
DISPLAY 0.680851 (-790 3160);
PAINT MONO (-790 3160);
FORCEPROP 0 LASTPIN (-800 1500) $PN 252
J 0
(-790 1510);
DISPLAY 0.680851 (-790 1510);
PAINT MONO (-790 1510);
FORCEPROP 0 LASTPIN (-800 3200) $PN 161
J 0
(-790 3210);
DISPLAY 0.680851 (-790 3210);
PAINT MONO (-790 3210);
FORCEPROP 0 LASTPIN (-800 1550) $PN 254
J 0
(-790 1560);
DISPLAY 0.680851 (-790 1560);
PAINT MONO (-790 1560);
FORCEPROP 0 LASTPIN (-800 3250) $PN 18
J 0
(-790 3260);
DISPLAY 0.680851 (-790 3260);
PAINT MONO (-790 3260);
FORCEPROP 0 LASTPIN (-800 1600) $PN 111
J 0
(-790 1610);
DISPLAY 0.680851 (-790 1610);
PAINT MONO (-790 1610);
FORCEPROP 0 LASTPIN (-800 3300) $PN 20
J 0
(-790 3310);
DISPLAY 0.680851 (-790 3310);
PAINT MONO (-790 3310);
FORCEPROP 0 LASTPIN (-800 1650) $PN 113
J 0
(-790 1660);
DISPLAY 0.680851 (-790 1660);
PAINT MONO (-790 1660);
FORCEPROP 0 LASTPIN (-800 3350) $PN 163
J 0
(-790 3360);
DISPLAY 0.680851 (-790 3360);
PAINT MONO (-790 3360);
FORCEPROP 0 LASTPIN (-800 1700) $PN 256
J 0
(-790 1710);
DISPLAY 0.680851 (-790 1710);
PAINT MONO (-790 1710);
FORCEPROP 0 LASTPIN (-800 3400) $PN 165
J 0
(-790 3410);
DISPLAY 0.680851 (-790 3410);
PAINT MONO (-790 3410);
FORCEPROP 0 LASTPIN (-800 1750) $PN 258
J 0
(-790 1760);
DISPLAY 0.680851 (-790 1760);
PAINT MONO (-790 1760);
FORCEPROP 0 LASTPIN (-800 3450) $PN 25
J 0
(-790 3460);
DISPLAY 0.680851 (-790 3460);
PAINT MONO (-790 3460);
FORCEPROP 0 LASTPIN (-800 1800) $PN 118
J 0
(-790 1810);
DISPLAY 0.680851 (-790 1810);
PAINT MONO (-790 1810);
FORCEPROP 0 LASTPIN (-800 3500) $PN 27
J 0
(-790 3510);
DISPLAY 0.680851 (-790 3510);
PAINT MONO (-790 3510);
FORCEPROP 0 LASTPIN (-800 1850) $PN 120
J 0
(-790 1860);
DISPLAY 0.680851 (-790 1860);
PAINT MONO (-790 1860);
FORCEPROP 0 LASTPIN (-800 3550) $PN 170
J 0
(-790 3560);
DISPLAY 0.680851 (-790 3560);
PAINT MONO (-790 3560);
FORCEPROP 0 LASTPIN (-800 1900) $PN 263
J 0
(-790 1910);
DISPLAY 0.680851 (-790 1910);
PAINT MONO (-790 1910);
FORCEPROP 0 LASTPIN (-800 3600) $PN 172
J 0
(-790 3610);
DISPLAY 0.680851 (-790 3610);
PAINT MONO (-790 3610);
FORCEPROP 0 LASTPIN (-800 1950) $PN 265
J 0
(-790 1960);
DISPLAY 0.680851 (-790 1960);
PAINT MONO (-790 1960);
FORCEPROP 0 LASTPIN (-800 3650) $PN 29
J 0
(-790 3660);
DISPLAY 0.680851 (-790 3660);
PAINT MONO (-790 3660);
FORCEPROP 0 LASTPIN (-800 2000) $PN 122
J 0
(-790 2010);
DISPLAY 0.680851 (-790 2010);
PAINT MONO (-790 2010);
FORCEPROP 0 LASTPIN (-800 3700) $PN 31
J 0
(-790 3710);
DISPLAY 0.680851 (-790 3710);
PAINT MONO (-790 3710);
FORCEPROP 0 LASTPIN (-800 2050) $PN 124
J 0
(-790 2060);
DISPLAY 0.680851 (-790 2060);
PAINT MONO (-790 2060);
FORCEPROP 0 LASTPIN (-800 3750) $PN 174
J 0
(-790 3760);
DISPLAY 0.680851 (-790 3760);
PAINT MONO (-790 3760);
FORCEPROP 0 LASTPIN (-800 2100) $PN 267
J 0
(-790 2110);
DISPLAY 0.680851 (-790 2110);
PAINT MONO (-790 2110);
FORCEPROP 0 LASTPIN (-800 3800) $PN 176
J 0
(-790 3810);
DISPLAY 0.680851 (-790 3810);
PAINT MONO (-790 3810);
FORCEPROP 0 LASTPIN (-800 2150) $PN 269
J 0
(-790 2160);
DISPLAY 0.680851 (-790 2160);
PAINT MONO (-790 2160);
FORCEPROP 0 LASTPIN (-800 3850) $PN 36
J 0
(-790 3860);
DISPLAY 0.680851 (-790 3860);
PAINT MONO (-790 3860);
FORCEPROP 0 LASTPIN (-800 2200) $PN 129
J 0
(-790 2210);
DISPLAY 0.680851 (-790 2210);
PAINT MONO (-790 2210);
FORCEPROP 0 LASTPIN (-800 3900) $PN 38
J 0
(-790 3910);
DISPLAY 0.680851 (-790 3910);
PAINT MONO (-790 3910);
FORCEPROP 0 LASTPIN (-800 2250) $PN 131
J 0
(-790 2260);
DISPLAY 0.680851 (-790 2260);
PAINT MONO (-790 2260);
FORCEPROP 0 LASTPIN (-800 3950) $PN 181
J 0
(-790 3960);
DISPLAY 0.680851 (-790 3960);
PAINT MONO (-790 3960);
FORCEPROP 0 LASTPIN (-800 2300) $PN 274
J 0
(-790 2310);
DISPLAY 0.680851 (-790 2310);
PAINT MONO (-790 2310);
FORCEPROP 0 LASTPIN (-800 4000) $PN 183
J 0
(-790 4010);
DISPLAY 0.680851 (-790 4010);
PAINT MONO (-790 4010);
FORCEPROP 0 LASTPIN (-800 2350) $PN 276
J 0
(-790 2360);
DISPLAY 0.680851 (-790 2360);
PAINT MONO (-790 2360);
FORCEPROP 0 LASTPIN (-800 4050) $PN 40
J 0
(-790 4060);
DISPLAY 0.680851 (-790 4060);
PAINT MONO (-790 4060);
FORCEPROP 0 LASTPIN (-800 2400) $PN 133
J 0
(-790 2410);
DISPLAY 0.680851 (-790 2410);
PAINT MONO (-790 2410);
FORCEPROP 0 LASTPIN (-800 4100) $PN 42
J 0
(-790 4110);
DISPLAY 0.680851 (-790 4110);
PAINT MONO (-790 4110);
FORCEPROP 0 LASTPIN (-800 2450) $PN 135
J 0
(-790 2460);
DISPLAY 0.680851 (-790 2460);
PAINT MONO (-790 2460);
FORCEPROP 0 LASTPIN (-800 4150) $PN 185
J 0
(-790 4160);
DISPLAY 0.680851 (-790 4160);
PAINT MONO (-790 4160);
FORCEPROP 0 LASTPIN (-800 2500) $PN 278
J 0
(-790 2510);
DISPLAY 0.680851 (-790 2510);
PAINT MONO (-790 2510);
FORCEPROP 0 LASTPIN (-800 4200) $PN 187
J 0
(-790 4210);
DISPLAY 0.680851 (-790 4210);
PAINT MONO (-790 4210);
FORCEPROP 0 LASTPIN (-800 2550) $PN 280
J 0
(-790 2560);
DISPLAY 0.680851 (-790 2560);
PAINT MONO (-790 2560);
FORCEPROP 0 LASTPIN (-800 4250) $PN 47
J 0
(-790 4260);
DISPLAY 0.680851 (-790 4260);
PAINT MONO (-790 4260);
FORCEPROP 0 LASTPIN (-800 2600) $PN 140
J 0
(-790 2610);
DISPLAY 0.680851 (-790 2610);
PAINT MONO (-790 2610);
FORCEPROP 0 LASTPIN (-800 4300) $PN 49
J 0
(-790 4310);
DISPLAY 0.680851 (-790 4310);
PAINT MONO (-790 4310);
FORCEPROP 0 LASTPIN (-800 2650) $PN 142
J 0
(-790 2660);
DISPLAY 0.680851 (-790 2660);
PAINT MONO (-790 2660);
FORCEPROP 0 LASTPIN (-800 4350) $PN 192
J 0
(-790 4360);
DISPLAY 0.680851 (-790 4360);
PAINT MONO (-790 4360);
FORCEPROP 0 LASTPIN (-800 2700) $PN 285
J 0
(-790 2710);
DISPLAY 0.680851 (-790 2710);
PAINT MONO (-790 2710);
FORCEPROP 0 LASTPIN (-800 4400) $PN 194
J 0
(-790 4410);
DISPLAY 0.680851 (-790 4410);
PAINT MONO (-790 4410);
FORCEPROP 0 LASTPIN (-800 2750) $PN 287
J 0
(-790 2760);
DISPLAY 0.680851 (-790 2760);
PAINT MONO (-790 2760);
FORCEPROP 0 LASTPIN (-2000 1900) $PN 148
J 2
(-2010 1910);
DISPLAY 0.680851 (-2010 1910);
PAINT MONO (-2010 1910);
FORCEPROP 0 LASTPIN (-2000 1800) $PN 4
J 2
(-2010 1810);
DISPLAY 0.680851 (-2010 1810);
PAINT MONO (-2010 1810);
FORCEPROP 0 LASTPIN (-2000 1850) $PN 5
J 2
(-2010 1860);
DISPLAY 0.680851 (-2010 1860);
PAINT MONO (-2010 1860);
FORCEPROP 0 LASTPIN (-2000 1000) $PN 86
J 2
(-2010 1010);
DISPLAY 0.680851 (-2010 1010);
PAINT MONO (-2010 1010);
FORCEPROP 0 LASTPIN (-2000 950) $PN 87
J 2
(-2010 960);
DISPLAY 0.680851 (-2010 960);
PAINT MONO (-2010 960);
FORCEPROP 0 LASTPIN (-2000 3600) $PN 74
J 2
(-2010 3610);
DISPLAY 0.680851 (-2010 3610);
PAINT MONO (-2010 3610);
FORCEPROP 0 LASTPIN (-2000 3550) $PN 227
J 2
(-2010 3560);
DISPLAY 0.680851 (-2010 3560);
PAINT MONO (-2010 3560);
FORCEPROP 0 LASTPIN (-2000 1550) $PN 147
J 2
(-2010 1560);
DISPLAY 0.680851 (-2010 1560);
PAINT MONO (-2010 1560);
FORCEPROP 0 LASTPIN (-2000 2100) $PN 207
J 2
(-2010 2110);
DISPLAY 0.680851 (-2010 2110);
PAINT MONO (-2010 2110);
FORCEPROP 0 LASTPIN (-2000 1150) $PN 2
J 2
(-2010 1160);
DISPLAY 0.680851 (-2010 1160);
PAINT MONO (-2010 1160);
FORCEPROP 0 LASTPIN (-2000 1200) $PN 144
J 2
(-2010 1210);
DISPLAY 0.680851 (-2010 1210);
PAINT MONO (-2010 1210);
FORCEPROP 0 LASTPIN (-2000 1250) $PN 149
J 2
(-2010 1260);
DISPLAY 0.680851 (-2010 1260);
PAINT MONO (-2010 1260);
FORCEPROP 0 LASTPIN (-2000 1300) $PN 150
J 2
(-2010 1310);
DISPLAY 0.680851 (-2010 1310);
PAINT MONO (-2010 1310);
FORCEPROP 0 LASTPIN (-2000 1350) $PN 220
J 2
(-2010 1360);
DISPLAY 0.680851 (-2010 1360);
PAINT MONO (-2010 1360);
FORCEPROP 0 LASTPIN (-2000 1400) $PN 231
J 2
(-2010 1410);
DISPLAY 0.680851 (-2010 1410);
PAINT MONO (-2010 1410);
FORCEPROP 0 LASTPIN (-2000 1450) $PN 232
J 2
(-2010 1460);
DISPLAY 0.680851 (-2010 1460);
PAINT MONO (-2010 1460);
FORCEPROP 0 LASTPIN (-2000 1950) $PN 3
J 2
(-2010 1960);
DISPLAY 0.680851 (-2010 1960);
PAINT MONO (-2010 1960);
FORCEPROP 1 LAST NEEDS_NO_SIZE TRUE
J 0
(-1400 2675);
DISPLAY 0.723404 (-1400 2675);
PAINT GREEN (-1400 2675);
DISPLAY INVISIBLE (-1400 2675);
FORCEPROP 1 LAST CDS_LMAN_SYM_OUTLINE -450,1875,450,-1875
J 0
(-1400 2675);
DISPLAY 0.468085 (-1400 2675);
PAINT GREEN (-1400 2675);
DISPLAY INVISIBLE (-1400 2675);
FORCEPROP 2 LAST CDS_LIB pure_quanta
J 0
(-1400 2675);
DISPLAY INVISIBLE (-1400 2675);
FORCEPROP 1 LAST PATH I25
J 0
(-1400 2675);
DISPLAY 0.723404 (-1400 2675);
PAINT GREEN (-1400 2675);
DISPLAY INVISIBLE (-1400 2675);
FORCEPROP 2 LAST CDS_LOCATION J19
J 0
(-1850 4900);
DISPLAY 1.021277 (-1850 4900);
DISPLAY INVISIBLE (-1850 4900);
FORCEPROP 0 LAST $SEC 1
J 0
(-1825 4900);
DISPLAY 0.680851 (-1825 4900);
PAINT MONO (-1825 4900);
DISPLAY INVISIBLE (-1825 4900);
FORCEPROP 2 LAST CDS_SEC 1
J 0
(-1850 4900);
DISPLAY 1.021277 (-1850 4900);
DISPLAY INVISIBLE (-1850 4900);
FORCEADD TAP..1
R 2
(-2225 2250);
FORCEPROP 3 LASTPIN (-2175 2250) SIG_NAME M_B_CPU1_SB_CB<1>
J 0
(-2165 2260);
DISPLAY 0.659574 (-2165 2260);
PAINT MONO (-2165 2260);
DISPLAY INVISIBLE (-2165 2260);
FORCEPROP 1 LASTPIN (-2175 2250) BN 1
J 2
(-2163 2258);
DISPLAY 0.680851 (-2163 2258);
PAINT GREEN (-2163 2258);
FORCEPROP 2 LAST CDS_LIB standard
J 0
(-2225 2250);
DISPLAY INVISIBLE (-2225 2250);
FORCEPROP 1 LAST BODY_TYPE PLUMBING
J 2
(-2225 2300);
DISPLAY 0.872340 (-2225 2300);
PAINT GREEN (-2225 2300);
DISPLAY INVISIBLE (-2225 2300);
FORCEPROP 1 LAST HDL_TAP TRUE
J 2
(-2550 2125);
DISPLAY 0.872340 (-2550 2125);
DISPLAY INVISIBLE (-2550 2125);
FORCEPROP 1 LAST PATH I26
J 2
(-2223 2250);
DISPLAY 0.872340 (-2223 2250);
PAINT GREEN (-2223 2250);
DISPLAY INVISIBLE (-2223 2250);
FORCEADD TAP..1
R 2
(-2225 2200);
FORCEPROP 3 LASTPIN (-2175 2200) SIG_NAME M_B_CPU1_SB_CB<0>
J 0
(-2165 2210);
DISPLAY 0.659574 (-2165 2210);
PAINT MONO (-2165 2210);
DISPLAY INVISIBLE (-2165 2210);
FORCEPROP 1 LASTPIN (-2175 2200) BN 0
J 2
(-2163 2208);
DISPLAY 0.680851 (-2163 2208);
PAINT GREEN (-2163 2208);
FORCEPROP 2 LAST CDS_LIB standard
J 0
(-2225 2200);
PAINT MONO (-2225 2200);
DISPLAY INVISIBLE (-2225 2200);
FORCEPROP 1 LAST BODY_TYPE PLUMBING
J 2
(-2225 2250);
DISPLAY 0.872340 (-2225 2250);
PAINT GREEN (-2225 2250);
DISPLAY INVISIBLE (-2225 2250);
FORCEPROP 1 LAST HDL_TAP TRUE
J 2
(-2550 2075);
DISPLAY 0.872340 (-2550 2075);
DISPLAY INVISIBLE (-2550 2075);
FORCEPROP 1 LAST PATH I27
J 2
(-2223 2200);
DISPLAY 0.872340 (-2223 2200);
PAINT GREEN (-2223 2200);
DISPLAY INVISIBLE (-2223 2200);
FORCEADD TAP..1
R 2
(-2225 2300);
FORCEPROP 3 LASTPIN (-2175 2300) SIG_NAME M_B_CPU1_SB_CB<2>
J 0
(-2165 2310);
DISPLAY 0.659574 (-2165 2310);
PAINT MONO (-2165 2310);
DISPLAY INVISIBLE (-2165 2310);
FORCEPROP 1 LASTPIN (-2175 2300) BN 2
J 2
(-2163 2308);
DISPLAY 0.680851 (-2163 2308);
PAINT GREEN (-2163 2308);
FORCEPROP 2 LAST CDS_LIB standard
J 0
(-2225 2300);
DISPLAY INVISIBLE (-2225 2300);
FORCEPROP 1 LAST BODY_TYPE PLUMBING
J 2
(-2225 2350);
DISPLAY 0.872340 (-2225 2350);
PAINT GREEN (-2225 2350);
DISPLAY INVISIBLE (-2225 2350);
FORCEPROP 1 LAST HDL_TAP TRUE
J 2
(-2550 2175);
DISPLAY 0.872340 (-2550 2175);
DISPLAY INVISIBLE (-2550 2175);
FORCEPROP 1 LAST PATH I28
J 2
(-2223 2300);
DISPLAY 0.872340 (-2223 2300);
PAINT GREEN (-2223 2300);
DISPLAY INVISIBLE (-2223 2300);
FORCEADD TAP..1
R 2
(-2225 2350);
FORCEPROP 3 LASTPIN (-2175 2350) SIG_NAME M_B_CPU1_SB_CB<3>
J 0
(-2165 2360);
DISPLAY 0.659574 (-2165 2360);
PAINT MONO (-2165 2360);
DISPLAY INVISIBLE (-2165 2360);
FORCEPROP 1 LASTPIN (-2175 2350) BN 3
J 2
(-2163 2358);
DISPLAY 0.680851 (-2163 2358);
PAINT GREEN (-2163 2358);
FORCEPROP 2 LAST CDS_LIB standard
J 0
(-2225 2350);
DISPLAY INVISIBLE (-2225 2350);
FORCEPROP 1 LAST BODY_TYPE PLUMBING
J 2
(-2225 2400);
DISPLAY 0.872340 (-2225 2400);
PAINT GREEN (-2225 2400);
DISPLAY INVISIBLE (-2225 2400);
FORCEPROP 1 LAST HDL_TAP TRUE
J 2
(-2550 2225);
DISPLAY 0.872340 (-2550 2225);
DISPLAY INVISIBLE (-2550 2225);
FORCEPROP 1 LAST PATH I29
J 2
(-2223 2350);
DISPLAY 0.872340 (-2223 2350);
PAINT GREEN (-2223 2350);
DISPLAY INVISIBLE (-2223 2350);
FORCEADD Q_RES..2
(-2000 250);
FORCEPROP 1 LAST PART_NUMBER CS32322FB03
J 0
(-1960 125);
DISPLAY 0.978723 (-1960 125);
DISPLAY INVISIBLE (-1960 125);
FORCEPROP 1 LAST VALUE 23.2K
J 0
(-1955 325);
DISPLAY 0.978723 (-1955 325);
FORCEPROP 1 LAST TOLERANCE 1%
J 0
(-1955 275);
DISPLAY 0.978723 (-1955 275);
FORCEPROP 1 LAST MATERIAL CHIP
J 0
(-1960 175);
DISPLAY 0.978723 (-1960 175);
FORCEPROP 1 LAST WATTAGE 1/16W
J 0
(-1960 225);
DISPLAY 0.978723 (-1960 225);
FORCEPROP 1 LAST PACK_TYPE 0402LF
J 0
(-1960 75);
DISPLAY 0.978723 (-1960 75);
FORCEPROP 1 LAST $LOCATION R44
J 0
(-1955 375);
DISPLAY 0.978723 (-1955 375);
FORCEPROP 1 LASTPIN (-2000 350) $PN 1
J 0
(-1995 312);
DISPLAY 0.787234 (-1995 312);
FORCEPROP 1 LASTPIN (-2000 150) $PN 2
J 0
(-1995 160);
DISPLAY 0.787234 (-1995 160);
FORCEPROP 2 LAST CDS_LIB pure_quanta
J 0
(-2000 250);
PAINT MONO (-2000 250);
DISPLAY INVISIBLE (-2000 250);
FORCEPROP 1 LAST PATH I3
J 0
(-1950 425);
DISPLAY 0.978723 (-1950 425);
PAINT WHITE (-1950 425);
DISPLAY INVISIBLE (-1950 425);
FORCEPROP 2 LAST CDS_LOCATION R44
J 0
(-1950 475);
DISPLAY 1.021277 (-1950 475);
DISPLAY INVISIBLE (-1950 475);
FORCEPROP 2 LAST $SEC 1
J 0
(-1950 475);
DISPLAY 0.680851 (-1950 475);
PAINT MONO (-1950 475);
DISPLAY INVISIBLE (-1950 475);
FORCEPROP 2 LAST CDS_SEC 1
J 0
(-1950 475);
DISPLAY 1.021277 (-1950 475);
DISPLAY INVISIBLE (-1950 475);
FORCEADD TAP..1
R 2
(-2225 2400);
FORCEPROP 3 LASTPIN (-2175 2400) SIG_NAME M_B_CPU1_SB_CB<4>
J 0
(-2165 2410);
DISPLAY 0.659574 (-2165 2410);
PAINT MONO (-2165 2410);
DISPLAY INVISIBLE (-2165 2410);
FORCEPROP 1 LASTPIN (-2175 2400) BN 4
J 2
(-2163 2408);
DISPLAY 0.680851 (-2163 2408);
PAINT GREEN (-2163 2408);
FORCEPROP 2 LAST CDS_LIB standard
J 0
(-2225 2400);
DISPLAY INVISIBLE (-2225 2400);
FORCEPROP 1 LAST BODY_TYPE PLUMBING
J 2
(-2225 2450);
DISPLAY 0.872340 (-2225 2450);
PAINT GREEN (-2225 2450);
DISPLAY INVISIBLE (-2225 2450);
FORCEPROP 1 LAST HDL_TAP TRUE
J 2
(-2550 2275);
DISPLAY 0.872340 (-2550 2275);
DISPLAY INVISIBLE (-2550 2275);
FORCEPROP 1 LAST PATH I30
J 2
(-2223 2400);
DISPLAY 0.872340 (-2223 2400);
PAINT GREEN (-2223 2400);
DISPLAY INVISIBLE (-2223 2400);
FORCEADD TAP..1
R 2
(-2225 2500);
FORCEPROP 3 LASTPIN (-2175 2500) SIG_NAME M_B_CPU1_SB_CB<6>
J 0
(-2165 2510);
DISPLAY 0.659574 (-2165 2510);
PAINT MONO (-2165 2510);
DISPLAY INVISIBLE (-2165 2510);
FORCEPROP 1 LASTPIN (-2175 2500) BN 6
J 2
(-2163 2508);
DISPLAY 0.680851 (-2163 2508);
PAINT GREEN (-2163 2508);
FORCEPROP 2 LAST CDS_LIB standard
J 0
(-2225 2500);
DISPLAY INVISIBLE (-2225 2500);
FORCEPROP 1 LAST BODY_TYPE PLUMBING
J 2
(-2225 2550);
DISPLAY 0.872340 (-2225 2550);
PAINT GREEN (-2225 2550);
DISPLAY INVISIBLE (-2225 2550);
FORCEPROP 1 LAST HDL_TAP TRUE
J 2
(-2550 2375);
DISPLAY 0.872340 (-2550 2375);
DISPLAY INVISIBLE (-2550 2375);
FORCEPROP 1 LAST PATH I31
J 2
(-2223 2500);
DISPLAY 0.872340 (-2223 2500);
PAINT GREEN (-2223 2500);
DISPLAY INVISIBLE (-2223 2500);
FORCEADD TAP..1
R 2
(-2225 2450);
FORCEPROP 3 LASTPIN (-2175 2450) SIG_NAME M_B_CPU1_SB_CB<5>
J 0
(-2165 2460);
DISPLAY 0.659574 (-2165 2460);
PAINT MONO (-2165 2460);
DISPLAY INVISIBLE (-2165 2460);
FORCEPROP 1 LASTPIN (-2175 2450) BN 5
J 2
(-2163 2458);
DISPLAY 0.680851 (-2163 2458);
PAINT GREEN (-2163 2458);
FORCEPROP 2 LAST CDS_LIB standard
J 0
(-2225 2450);
DISPLAY INVISIBLE (-2225 2450);
FORCEPROP 1 LAST BODY_TYPE PLUMBING
J 2
(-2225 2500);
DISPLAY 0.872340 (-2225 2500);
PAINT GREEN (-2225 2500);
DISPLAY INVISIBLE (-2225 2500);
FORCEPROP 1 LAST HDL_TAP TRUE
J 2
(-2550 2325);
DISPLAY 0.872340 (-2550 2325);
DISPLAY INVISIBLE (-2550 2325);
FORCEPROP 1 LAST PATH I32
J 2
(-2223 2450);
DISPLAY 0.872340 (-2223 2450);
PAINT GREEN (-2223 2450);
DISPLAY INVISIBLE (-2223 2450);
FORCEADD TAP..1
(-575 1250);
FORCEPROP 3 LASTPIN (-625 1250) SIG_NAME M_B_CPU1_SB_DQ<1>
J 0
(-615 1260);
DISPLAY 0.659574 (-615 1260);
PAINT MONO (-615 1260);
DISPLAY INVISIBLE (-615 1260);
FORCEPROP 1 LASTPIN (-625 1250) BN 1
J 0
(-637 1258);
DISPLAY 0.680851 (-637 1258);
PAINT GREEN (-637 1258);
FORCEPROP 2 LAST CDS_LIB standard
J 0
(-575 1250);
PAINT MONO (-575 1250);
DISPLAY INVISIBLE (-575 1250);
FORCEPROP 1 LAST BODY_TYPE PLUMBING
J 0
(-575 1300);
DISPLAY 0.872340 (-575 1300);
PAINT GREEN (-575 1300);
DISPLAY INVISIBLE (-575 1300);
FORCEPROP 1 LAST HDL_TAP TRUE
J 0
(-250 1125);
DISPLAY 0.872340 (-250 1125);
DISPLAY INVISIBLE (-250 1125);
FORCEPROP 1 LAST PATH I33
J 0
(-577 1250);
DISPLAY 0.872340 (-577 1250);
PAINT GREEN (-577 1250);
DISPLAY INVISIBLE (-577 1250);
FORCEADD TAP..1
(-575 1200);
FORCEPROP 3 LASTPIN (-625 1200) SIG_NAME M_B_CPU1_SB_DQ<0>
J 0
(-615 1210);
DISPLAY 0.659574 (-615 1210);
PAINT MONO (-615 1210);
DISPLAY INVISIBLE (-615 1210);
FORCEPROP 1 LASTPIN (-625 1200) BN 0
J 0
(-637 1208);
DISPLAY 0.680851 (-637 1208);
PAINT GREEN (-637 1208);
FORCEPROP 2 LAST CDS_LIB standard
J 0
(-575 1200);
PAINT MONO (-575 1200);
DISPLAY INVISIBLE (-575 1200);
FORCEPROP 1 LAST BODY_TYPE PLUMBING
J 0
(-575 1250);
DISPLAY 0.872340 (-575 1250);
PAINT GREEN (-575 1250);
DISPLAY INVISIBLE (-575 1250);
FORCEPROP 1 LAST HDL_TAP TRUE
J 0
(-250 1075);
DISPLAY 0.872340 (-250 1075);
DISPLAY INVISIBLE (-250 1075);
FORCEPROP 1 LAST PATH I34
J 0
(-577 1200);
DISPLAY 0.872340 (-577 1200);
PAINT GREEN (-577 1200);
DISPLAY INVISIBLE (-577 1200);
FORCEADD TAP..1
(-575 1350);
FORCEPROP 3 LASTPIN (-625 1350) SIG_NAME M_B_CPU1_SB_DQ<3>
J 0
(-615 1360);
DISPLAY 0.659574 (-615 1360);
PAINT MONO (-615 1360);
DISPLAY INVISIBLE (-615 1360);
FORCEPROP 1 LASTPIN (-625 1350) BN 3
J 0
(-637 1358);
DISPLAY 0.680851 (-637 1358);
PAINT GREEN (-637 1358);
FORCEPROP 2 LAST CDS_LIB standard
J 0
(-575 1350);
PAINT MONO (-575 1350);
DISPLAY INVISIBLE (-575 1350);
FORCEPROP 1 LAST BODY_TYPE PLUMBING
J 0
(-575 1400);
DISPLAY 0.872340 (-575 1400);
PAINT GREEN (-575 1400);
DISPLAY INVISIBLE (-575 1400);
FORCEPROP 1 LAST HDL_TAP TRUE
J 0
(-250 1225);
DISPLAY 0.872340 (-250 1225);
DISPLAY INVISIBLE (-250 1225);
FORCEPROP 1 LAST PATH I35
J 0
(-577 1350);
DISPLAY 0.872340 (-577 1350);
PAINT GREEN (-577 1350);
DISPLAY INVISIBLE (-577 1350);
FORCEADD TAP..1
(-575 1300);
FORCEPROP 3 LASTPIN (-625 1300) SIG_NAME M_B_CPU1_SB_DQ<2>
J 0
(-615 1310);
DISPLAY 0.659574 (-615 1310);
PAINT MONO (-615 1310);
DISPLAY INVISIBLE (-615 1310);
FORCEPROP 1 LASTPIN (-625 1300) BN 2
J 0
(-637 1308);
DISPLAY 0.680851 (-637 1308);
PAINT GREEN (-637 1308);
FORCEPROP 2 LAST CDS_LIB standard
J 0
(-575 1300);
PAINT MONO (-575 1300);
DISPLAY INVISIBLE (-575 1300);
FORCEPROP 1 LAST BODY_TYPE PLUMBING
J 0
(-575 1350);
DISPLAY 0.872340 (-575 1350);
PAINT GREEN (-575 1350);
DISPLAY INVISIBLE (-575 1350);
FORCEPROP 1 LAST HDL_TAP TRUE
J 0
(-250 1175);
DISPLAY 0.872340 (-250 1175);
DISPLAY INVISIBLE (-250 1175);
FORCEPROP 1 LAST PATH I36
J 0
(-577 1300);
DISPLAY 0.872340 (-577 1300);
PAINT GREEN (-577 1300);
DISPLAY INVISIBLE (-577 1300);
FORCEADD TAP..1
(-575 1450);
FORCEPROP 3 LASTPIN (-625 1450) SIG_NAME M_B_CPU1_SB_DQ<5>
J 0
(-615 1460);
DISPLAY 0.659574 (-615 1460);
PAINT MONO (-615 1460);
DISPLAY INVISIBLE (-615 1460);
FORCEPROP 1 LASTPIN (-625 1450) BN 5
J 0
(-637 1458);
DISPLAY 0.680851 (-637 1458);
PAINT GREEN (-637 1458);
FORCEPROP 2 LAST CDS_LIB standard
J 0
(-575 1450);
PAINT MONO (-575 1450);
DISPLAY INVISIBLE (-575 1450);
FORCEPROP 1 LAST BODY_TYPE PLUMBING
J 0
(-575 1500);
DISPLAY 0.872340 (-575 1500);
PAINT GREEN (-575 1500);
DISPLAY INVISIBLE (-575 1500);
FORCEPROP 1 LAST HDL_TAP TRUE
J 0
(-250 1325);
DISPLAY 0.872340 (-250 1325);
DISPLAY INVISIBLE (-250 1325);
FORCEPROP 1 LAST PATH I37
J 0
(-577 1450);
DISPLAY 0.872340 (-577 1450);
PAINT GREEN (-577 1450);
DISPLAY INVISIBLE (-577 1450);
FORCEADD TAP..1
(-575 1400);
FORCEPROP 3 LASTPIN (-625 1400) SIG_NAME M_B_CPU1_SB_DQ<4>
J 0
(-615 1410);
DISPLAY 0.659574 (-615 1410);
PAINT MONO (-615 1410);
DISPLAY INVISIBLE (-615 1410);
FORCEPROP 1 LASTPIN (-625 1400) BN 4
J 0
(-637 1408);
DISPLAY 0.680851 (-637 1408);
PAINT GREEN (-637 1408);
FORCEPROP 2 LAST CDS_LIB standard
J 0
(-575 1400);
PAINT MONO (-575 1400);
DISPLAY INVISIBLE (-575 1400);
FORCEPROP 1 LAST BODY_TYPE PLUMBING
J 0
(-575 1450);
DISPLAY 0.872340 (-575 1450);
PAINT GREEN (-575 1450);
DISPLAY INVISIBLE (-575 1450);
FORCEPROP 1 LAST HDL_TAP TRUE
J 0
(-250 1275);
DISPLAY 0.872340 (-250 1275);
DISPLAY INVISIBLE (-250 1275);
FORCEPROP 1 LAST PATH I38
J 0
(-577 1400);
DISPLAY 0.872340 (-577 1400);
PAINT GREEN (-577 1400);
DISPLAY INVISIBLE (-577 1400);
FORCEADD TAP..1
(-575 1500);
FORCEPROP 3 LASTPIN (-625 1500) SIG_NAME M_B_CPU1_SB_DQ<6>
J 0
(-615 1510);
DISPLAY 0.659574 (-615 1510);
PAINT MONO (-615 1510);
DISPLAY INVISIBLE (-615 1510);
FORCEPROP 1 LASTPIN (-625 1500) BN 6
J 0
(-637 1508);
DISPLAY 0.680851 (-637 1508);
PAINT GREEN (-637 1508);
FORCEPROP 2 LAST CDS_LIB standard
J 0
(-575 1500);
PAINT MONO (-575 1500);
DISPLAY INVISIBLE (-575 1500);
FORCEPROP 1 LAST BODY_TYPE PLUMBING
J 0
(-575 1550);
DISPLAY 0.872340 (-575 1550);
PAINT GREEN (-575 1550);
DISPLAY INVISIBLE (-575 1550);
FORCEPROP 1 LAST HDL_TAP TRUE
J 0
(-250 1375);
DISPLAY 0.872340 (-250 1375);
DISPLAY INVISIBLE (-250 1375);
FORCEPROP 1 LAST PATH I39
J 0
(-577 1500);
DISPLAY 0.872340 (-577 1500);
PAINT GREEN (-577 1500);
DISPLAY INVISIBLE (-577 1500);
FORCEADD OFFPAGE..2
R 2
(-3150 950);
FORCEPROP 2 LAST $XR0 52 
J 0
(-3374 950);
DISPLAY 0.638298 (-3374 950);
PAINT MONO (-3374 950);
FORCEPROP 2 LAST CDS_LIB standard
J 0
(-3150 950);
PAINT MONO (-3150 950);
DISPLAY INVISIBLE (-3150 950);
FORCEPROP 1 LAST OFFPAGE TRUE
J 2
(-3475 825);
DISPLAY 0.872340 (-3475 825);
DISPLAY INVISIBLE (-3475 825);
FORCEPROP 1 LAST COMMENT_BODY TRUE
J 2
(-3105 855);
DISPLAY 0.872340 (-3105 855);
PAINT GREEN (-3105 855);
DISPLAY INVISIBLE (-3105 855);
FORCEPROP 2 LAST PATH I4
J 0
(-3100 1025);
DISPLAY 1.021277 (-3100 1025);
DISPLAY INVISIBLE (-3100 1025);
FORCEADD TAP..1
(-575 1550);
FORCEPROP 3 LASTPIN (-625 1550) SIG_NAME M_B_CPU1_SB_DQ<7>
J 0
(-615 1560);
DISPLAY 0.659574 (-615 1560);
PAINT MONO (-615 1560);
DISPLAY INVISIBLE (-615 1560);
FORCEPROP 1 LASTPIN (-625 1550) BN 7
J 0
(-637 1558);
DISPLAY 0.680851 (-637 1558);
PAINT GREEN (-637 1558);
FORCEPROP 2 LAST CDS_LIB standard
J 0
(-575 1550);
PAINT MONO (-575 1550);
DISPLAY INVISIBLE (-575 1550);
FORCEPROP 1 LAST BODY_TYPE PLUMBING
J 0
(-575 1600);
DISPLAY 0.872340 (-575 1600);
PAINT GREEN (-575 1600);
DISPLAY INVISIBLE (-575 1600);
FORCEPROP 1 LAST HDL_TAP TRUE
J 0
(-250 1425);
DISPLAY 0.872340 (-250 1425);
DISPLAY INVISIBLE (-250 1425);
FORCEPROP 1 LAST PATH I40
J 0
(-577 1550);
DISPLAY 0.872340 (-577 1550);
PAINT GREEN (-577 1550);
DISPLAY INVISIBLE (-577 1550);
FORCEADD TAP..1
(-575 1600);
FORCEPROP 3 LASTPIN (-625 1600) SIG_NAME M_B_CPU1_SB_DQ<8>
J 0
(-615 1610);
DISPLAY 0.659574 (-615 1610);
PAINT MONO (-615 1610);
DISPLAY INVISIBLE (-615 1610);
FORCEPROP 1 LASTPIN (-625 1600) BN 8
J 0
(-637 1608);
DISPLAY 0.680851 (-637 1608);
PAINT GREEN (-637 1608);
FORCEPROP 2 LAST CDS_LIB standard
J 0
(-575 1600);
PAINT MONO (-575 1600);
DISPLAY INVISIBLE (-575 1600);
FORCEPROP 1 LAST BODY_TYPE PLUMBING
J 0
(-575 1650);
DISPLAY 0.872340 (-575 1650);
PAINT GREEN (-575 1650);
DISPLAY INVISIBLE (-575 1650);
FORCEPROP 1 LAST HDL_TAP TRUE
J 0
(-250 1475);
DISPLAY 0.872340 (-250 1475);
DISPLAY INVISIBLE (-250 1475);
FORCEPROP 1 LAST PATH I41
J 0
(-577 1600);
DISPLAY 0.872340 (-577 1600);
PAINT GREEN (-577 1600);
DISPLAY INVISIBLE (-577 1600);
FORCEADD TAP..1
(-575 1650);
FORCEPROP 3 LASTPIN (-625 1650) SIG_NAME M_B_CPU1_SB_DQ<9>
J 0
(-615 1660);
DISPLAY 0.659574 (-615 1660);
PAINT MONO (-615 1660);
DISPLAY INVISIBLE (-615 1660);
FORCEPROP 1 LASTPIN (-625 1650) BN 9
J 0
(-637 1658);
DISPLAY 0.680851 (-637 1658);
PAINT GREEN (-637 1658);
FORCEPROP 2 LAST CDS_LIB standard
J 0
(-575 1650);
PAINT MONO (-575 1650);
DISPLAY INVISIBLE (-575 1650);
FORCEPROP 1 LAST BODY_TYPE PLUMBING
J 0
(-575 1700);
DISPLAY 0.872340 (-575 1700);
PAINT GREEN (-575 1700);
DISPLAY INVISIBLE (-575 1700);
FORCEPROP 1 LAST HDL_TAP TRUE
J 0
(-250 1525);
DISPLAY 0.872340 (-250 1525);
DISPLAY INVISIBLE (-250 1525);
FORCEPROP 1 LAST PATH I42
J 0
(-577 1650);
DISPLAY 0.872340 (-577 1650);
PAINT GREEN (-577 1650);
DISPLAY INVISIBLE (-577 1650);
FORCEADD TAP..1
(-575 1750);
FORCEPROP 3 LASTPIN (-625 1750) SIG_NAME M_B_CPU1_SB_DQ<11>
J 0
(-615 1760);
DISPLAY 0.659574 (-615 1760);
PAINT MONO (-615 1760);
DISPLAY INVISIBLE (-615 1760);
FORCEPROP 1 LASTPIN (-625 1750) BN 11
J 0
(-637 1758);
DISPLAY 0.680851 (-637 1758);
PAINT GREEN (-637 1758);
FORCEPROP 2 LAST CDS_LIB standard
J 0
(-575 1750);
PAINT MONO (-575 1750);
DISPLAY INVISIBLE (-575 1750);
FORCEPROP 1 LAST BODY_TYPE PLUMBING
J 0
(-575 1800);
DISPLAY 0.872340 (-575 1800);
PAINT GREEN (-575 1800);
DISPLAY INVISIBLE (-575 1800);
FORCEPROP 1 LAST HDL_TAP TRUE
J 0
(-250 1625);
DISPLAY 0.872340 (-250 1625);
DISPLAY INVISIBLE (-250 1625);
FORCEPROP 1 LAST PATH I43
J 0
(-577 1750);
DISPLAY 0.872340 (-577 1750);
PAINT GREEN (-577 1750);
DISPLAY INVISIBLE (-577 1750);
FORCEADD TAP..1
(-575 1700);
FORCEPROP 3 LASTPIN (-625 1700) SIG_NAME M_B_CPU1_SB_DQ<10>
J 0
(-615 1710);
DISPLAY 0.659574 (-615 1710);
PAINT MONO (-615 1710);
DISPLAY INVISIBLE (-615 1710);
FORCEPROP 1 LASTPIN (-625 1700) BN 10
J 0
(-637 1708);
DISPLAY 0.680851 (-637 1708);
PAINT GREEN (-637 1708);
FORCEPROP 2 LAST CDS_LIB standard
J 0
(-575 1700);
PAINT MONO (-575 1700);
DISPLAY INVISIBLE (-575 1700);
FORCEPROP 1 LAST BODY_TYPE PLUMBING
J 0
(-575 1750);
DISPLAY 0.872340 (-575 1750);
PAINT GREEN (-575 1750);
DISPLAY INVISIBLE (-575 1750);
FORCEPROP 1 LAST HDL_TAP TRUE
J 0
(-250 1575);
DISPLAY 0.872340 (-250 1575);
DISPLAY INVISIBLE (-250 1575);
FORCEPROP 1 LAST PATH I44
J 0
(-577 1700);
DISPLAY 0.872340 (-577 1700);
PAINT GREEN (-577 1700);
DISPLAY INVISIBLE (-577 1700);
FORCEADD TAP..1
(-575 1950);
FORCEPROP 3 LASTPIN (-625 1950) SIG_NAME M_B_CPU1_SB_DQ<15>
J 0
(-615 1960);
DISPLAY 0.659574 (-615 1960);
PAINT MONO (-615 1960);
DISPLAY INVISIBLE (-615 1960);
FORCEPROP 1 LASTPIN (-625 1950) BN 15
J 0
(-637 1958);
DISPLAY 0.680851 (-637 1958);
PAINT GREEN (-637 1958);
FORCEPROP 2 LAST CDS_LIB standard
J 0
(-575 1950);
PAINT MONO (-575 1950);
DISPLAY INVISIBLE (-575 1950);
FORCEPROP 1 LAST BODY_TYPE PLUMBING
J 0
(-575 2000);
DISPLAY 0.872340 (-575 2000);
PAINT GREEN (-575 2000);
DISPLAY INVISIBLE (-575 2000);
FORCEPROP 1 LAST HDL_TAP TRUE
J 0
(-250 1825);
DISPLAY 0.872340 (-250 1825);
DISPLAY INVISIBLE (-250 1825);
FORCEPROP 1 LAST PATH I45
J 0
(-577 1950);
DISPLAY 0.872340 (-577 1950);
PAINT GREEN (-577 1950);
DISPLAY INVISIBLE (-577 1950);
FORCEADD TAP..1
(-575 2000);
FORCEPROP 3 LASTPIN (-625 2000) SIG_NAME M_B_CPU1_SB_DQ<16>
J 0
(-615 2010);
DISPLAY 0.659574 (-615 2010);
PAINT MONO (-615 2010);
DISPLAY INVISIBLE (-615 2010);
FORCEPROP 1 LASTPIN (-625 2000) BN 16
J 0
(-637 2008);
DISPLAY 0.680851 (-637 2008);
PAINT GREEN (-637 2008);
FORCEPROP 2 LAST CDS_LIB standard
J 0
(-575 2000);
PAINT MONO (-575 2000);
DISPLAY INVISIBLE (-575 2000);
FORCEPROP 1 LAST BODY_TYPE PLUMBING
J 0
(-575 2050);
DISPLAY 0.872340 (-575 2050);
PAINT GREEN (-575 2050);
DISPLAY INVISIBLE (-575 2050);
FORCEPROP 1 LAST HDL_TAP TRUE
J 0
(-250 1875);
DISPLAY 0.872340 (-250 1875);
DISPLAY INVISIBLE (-250 1875);
FORCEPROP 1 LAST PATH I46
J 0
(-577 2000);
DISPLAY 0.872340 (-577 2000);
PAINT GREEN (-577 2000);
DISPLAY INVISIBLE (-577 2000);
FORCEADD TAP..1
(-575 1900);
FORCEPROP 3 LASTPIN (-625 1900) SIG_NAME M_B_CPU1_SB_DQ<14>
J 0
(-615 1910);
DISPLAY 0.659574 (-615 1910);
PAINT MONO (-615 1910);
DISPLAY INVISIBLE (-615 1910);
FORCEPROP 1 LASTPIN (-625 1900) BN 14
J 0
(-637 1908);
DISPLAY 0.680851 (-637 1908);
PAINT GREEN (-637 1908);
FORCEPROP 2 LAST CDS_LIB standard
J 0
(-575 1900);
PAINT MONO (-575 1900);
DISPLAY INVISIBLE (-575 1900);
FORCEPROP 1 LAST BODY_TYPE PLUMBING
J 0
(-575 1950);
DISPLAY 0.872340 (-575 1950);
PAINT GREEN (-575 1950);
DISPLAY INVISIBLE (-575 1950);
FORCEPROP 1 LAST HDL_TAP TRUE
J 0
(-250 1775);
DISPLAY 0.872340 (-250 1775);
DISPLAY INVISIBLE (-250 1775);
FORCEPROP 1 LAST PATH I47
J 0
(-577 1900);
DISPLAY 0.872340 (-577 1900);
PAINT GREEN (-577 1900);
DISPLAY INVISIBLE (-577 1900);
FORCEADD TAP..1
(-575 1850);
FORCEPROP 3 LASTPIN (-625 1850) SIG_NAME M_B_CPU1_SB_DQ<13>
J 0
(-615 1860);
DISPLAY 0.659574 (-615 1860);
PAINT MONO (-615 1860);
DISPLAY INVISIBLE (-615 1860);
FORCEPROP 1 LASTPIN (-625 1850) BN 13
J 0
(-637 1858);
DISPLAY 0.680851 (-637 1858);
PAINT GREEN (-637 1858);
FORCEPROP 2 LAST CDS_LIB standard
J 0
(-575 1850);
PAINT MONO (-575 1850);
DISPLAY INVISIBLE (-575 1850);
FORCEPROP 1 LAST BODY_TYPE PLUMBING
J 0
(-575 1900);
DISPLAY 0.872340 (-575 1900);
PAINT GREEN (-575 1900);
DISPLAY INVISIBLE (-575 1900);
FORCEPROP 1 LAST HDL_TAP TRUE
J 0
(-250 1725);
DISPLAY 0.872340 (-250 1725);
DISPLAY INVISIBLE (-250 1725);
FORCEPROP 1 LAST PATH I48
J 0
(-577 1850);
DISPLAY 0.872340 (-577 1850);
PAINT GREEN (-577 1850);
DISPLAY INVISIBLE (-577 1850);
FORCEADD TAP..1
(-575 1800);
FORCEPROP 3 LASTPIN (-625 1800) SIG_NAME M_B_CPU1_SB_DQ<12>
J 0
(-615 1810);
DISPLAY 0.659574 (-615 1810);
PAINT MONO (-615 1810);
DISPLAY INVISIBLE (-615 1810);
FORCEPROP 1 LASTPIN (-625 1800) BN 12
J 0
(-637 1808);
DISPLAY 0.680851 (-637 1808);
PAINT GREEN (-637 1808);
FORCEPROP 2 LAST CDS_LIB standard
J 0
(-575 1800);
PAINT MONO (-575 1800);
DISPLAY INVISIBLE (-575 1800);
FORCEPROP 1 LAST BODY_TYPE PLUMBING
J 0
(-575 1850);
DISPLAY 0.872340 (-575 1850);
PAINT GREEN (-575 1850);
DISPLAY INVISIBLE (-575 1850);
FORCEPROP 1 LAST HDL_TAP TRUE
J 0
(-250 1675);
DISPLAY 0.872340 (-250 1675);
DISPLAY INVISIBLE (-250 1675);
FORCEPROP 1 LAST PATH I49
J 0
(-577 1800);
DISPLAY 0.872340 (-577 1800);
PAINT GREEN (-577 1800);
DISPLAY INVISIBLE (-577 1800);
FORCEADD OFFPAGE..2
R 2
(-3150 1000);
FORCEPROP 2 LAST $XR0 52 
J 0
(-3374 1000);
DISPLAY 0.638298 (-3374 1000);
PAINT MONO (-3374 1000);
FORCEPROP 2 LAST CDS_LIB standard
J 0
(-3150 1000);
PAINT MONO (-3150 1000);
DISPLAY INVISIBLE (-3150 1000);
FORCEPROP 1 LAST OFFPAGE TRUE
J 2
(-3475 875);
DISPLAY 0.872340 (-3475 875);
DISPLAY INVISIBLE (-3475 875);
FORCEPROP 1 LAST COMMENT_BODY TRUE
J 2
(-3105 905);
DISPLAY 0.872340 (-3105 905);
PAINT GREEN (-3105 905);
DISPLAY INVISIBLE (-3105 905);
FORCEPROP 2 LAST PATH I5
J 0
(-3100 1075);
DISPLAY 1.021277 (-3100 1075);
DISPLAY INVISIBLE (-3100 1075);
FORCEADD TAP..1
(-575 2250);
FORCEPROP 3 LASTPIN (-625 2250) SIG_NAME M_B_CPU1_SB_DQ<21>
J 0
(-615 2260);
DISPLAY 0.659574 (-615 2260);
PAINT MONO (-615 2260);
DISPLAY INVISIBLE (-615 2260);
FORCEPROP 1 LASTPIN (-625 2250) BN 21
J 0
(-637 2258);
DISPLAY 0.680851 (-637 2258);
PAINT GREEN (-637 2258);
FORCEPROP 2 LAST CDS_LIB standard
J 0
(-575 2250);
PAINT MONO (-575 2250);
DISPLAY INVISIBLE (-575 2250);
FORCEPROP 1 LAST BODY_TYPE PLUMBING
J 0
(-575 2300);
DISPLAY 0.872340 (-575 2300);
PAINT GREEN (-575 2300);
DISPLAY INVISIBLE (-575 2300);
FORCEPROP 1 LAST HDL_TAP TRUE
J 0
(-250 2125);
DISPLAY 0.872340 (-250 2125);
DISPLAY INVISIBLE (-250 2125);
FORCEPROP 1 LAST PATH I50
J 0
(-577 2250);
DISPLAY 0.872340 (-577 2250);
PAINT GREEN (-577 2250);
DISPLAY INVISIBLE (-577 2250);
FORCEADD TAP..1
(-575 2200);
FORCEPROP 3 LASTPIN (-625 2200) SIG_NAME M_B_CPU1_SB_DQ<20>
J 0
(-615 2210);
DISPLAY 0.659574 (-615 2210);
PAINT MONO (-615 2210);
DISPLAY INVISIBLE (-615 2210);
FORCEPROP 1 LASTPIN (-625 2200) BN 20
J 0
(-637 2208);
DISPLAY 0.680851 (-637 2208);
PAINT GREEN (-637 2208);
FORCEPROP 2 LAST CDS_LIB standard
J 0
(-575 2200);
PAINT MONO (-575 2200);
DISPLAY INVISIBLE (-575 2200);
FORCEPROP 1 LAST BODY_TYPE PLUMBING
J 0
(-575 2250);
DISPLAY 0.872340 (-575 2250);
PAINT GREEN (-575 2250);
DISPLAY INVISIBLE (-575 2250);
FORCEPROP 1 LAST HDL_TAP TRUE
J 0
(-250 2075);
DISPLAY 0.872340 (-250 2075);
DISPLAY INVISIBLE (-250 2075);
FORCEPROP 1 LAST PATH I51
J 0
(-577 2200);
DISPLAY 0.872340 (-577 2200);
PAINT GREEN (-577 2200);
DISPLAY INVISIBLE (-577 2200);
FORCEADD TAP..1
(-575 2150);
FORCEPROP 3 LASTPIN (-625 2150) SIG_NAME M_B_CPU1_SB_DQ<19>
J 0
(-615 2160);
DISPLAY 0.659574 (-615 2160);
PAINT MONO (-615 2160);
DISPLAY INVISIBLE (-615 2160);
FORCEPROP 1 LASTPIN (-625 2150) BN 19
J 0
(-637 2158);
DISPLAY 0.680851 (-637 2158);
PAINT GREEN (-637 2158);
FORCEPROP 2 LAST CDS_LIB standard
J 0
(-575 2150);
PAINT MONO (-575 2150);
DISPLAY INVISIBLE (-575 2150);
FORCEPROP 1 LAST BODY_TYPE PLUMBING
J 0
(-575 2200);
DISPLAY 0.872340 (-575 2200);
PAINT GREEN (-575 2200);
DISPLAY INVISIBLE (-575 2200);
FORCEPROP 1 LAST HDL_TAP TRUE
J 0
(-250 2025);
DISPLAY 0.872340 (-250 2025);
DISPLAY INVISIBLE (-250 2025);
FORCEPROP 1 LAST PATH I52
J 0
(-577 2150);
DISPLAY 0.872340 (-577 2150);
PAINT GREEN (-577 2150);
DISPLAY INVISIBLE (-577 2150);
FORCEADD TAP..1
(-575 2100);
FORCEPROP 3 LASTPIN (-625 2100) SIG_NAME M_B_CPU1_SB_DQ<18>
J 0
(-615 2110);
DISPLAY 0.659574 (-615 2110);
PAINT MONO (-615 2110);
DISPLAY INVISIBLE (-615 2110);
FORCEPROP 1 LASTPIN (-625 2100) BN 18
J 0
(-637 2108);
DISPLAY 0.680851 (-637 2108);
PAINT GREEN (-637 2108);
FORCEPROP 2 LAST CDS_LIB standard
J 0
(-575 2100);
PAINT MONO (-575 2100);
DISPLAY INVISIBLE (-575 2100);
FORCEPROP 1 LAST BODY_TYPE PLUMBING
J 0
(-575 2150);
DISPLAY 0.872340 (-575 2150);
PAINT GREEN (-575 2150);
DISPLAY INVISIBLE (-575 2150);
FORCEPROP 1 LAST HDL_TAP TRUE
J 0
(-250 1975);
DISPLAY 0.872340 (-250 1975);
DISPLAY INVISIBLE (-250 1975);
FORCEPROP 1 LAST PATH I53
J 0
(-577 2100);
DISPLAY 0.872340 (-577 2100);
PAINT GREEN (-577 2100);
DISPLAY INVISIBLE (-577 2100);
FORCEADD TAP..1
(-575 2050);
FORCEPROP 3 LASTPIN (-625 2050) SIG_NAME M_B_CPU1_SB_DQ<17>
J 0
(-615 2060);
DISPLAY 0.659574 (-615 2060);
PAINT MONO (-615 2060);
DISPLAY INVISIBLE (-615 2060);
FORCEPROP 1 LASTPIN (-625 2050) BN 17
J 0
(-637 2058);
DISPLAY 0.680851 (-637 2058);
PAINT GREEN (-637 2058);
FORCEPROP 2 LAST CDS_LIB standard
J 0
(-575 2050);
PAINT MONO (-575 2050);
DISPLAY INVISIBLE (-575 2050);
FORCEPROP 1 LAST BODY_TYPE PLUMBING
J 0
(-575 2100);
DISPLAY 0.872340 (-575 2100);
PAINT GREEN (-575 2100);
DISPLAY INVISIBLE (-575 2100);
FORCEPROP 1 LAST HDL_TAP TRUE
J 0
(-250 1925);
DISPLAY 0.872340 (-250 1925);
DISPLAY INVISIBLE (-250 1925);
FORCEPROP 1 LAST PATH I54
J 0
(-577 2050);
DISPLAY 0.872340 (-577 2050);
PAINT GREEN (-577 2050);
DISPLAY INVISIBLE (-577 2050);
FORCEADD TAP..1
(-575 2450);
FORCEPROP 3 LASTPIN (-625 2450) SIG_NAME M_B_CPU1_SB_DQ<25>
J 0
(-615 2460);
DISPLAY 0.659574 (-615 2460);
PAINT MONO (-615 2460);
DISPLAY INVISIBLE (-615 2460);
FORCEPROP 1 LASTPIN (-625 2450) BN 25
J 0
(-637 2458);
DISPLAY 0.680851 (-637 2458);
PAINT GREEN (-637 2458);
FORCEPROP 2 LAST CDS_LIB standard
J 0
(-575 2450);
DISPLAY INVISIBLE (-575 2450);
FORCEPROP 1 LAST BODY_TYPE PLUMBING
J 0
(-575 2500);
DISPLAY 0.872340 (-575 2500);
PAINT GREEN (-575 2500);
DISPLAY INVISIBLE (-575 2500);
FORCEPROP 1 LAST HDL_TAP TRUE
J 0
(-250 2325);
DISPLAY 0.872340 (-250 2325);
DISPLAY INVISIBLE (-250 2325);
FORCEPROP 1 LAST PATH I55
J 0
(-577 2450);
DISPLAY 0.872340 (-577 2450);
PAINT GREEN (-577 2450);
DISPLAY INVISIBLE (-577 2450);
FORCEADD TAP..1
(-575 2500);
FORCEPROP 3 LASTPIN (-625 2500) SIG_NAME M_B_CPU1_SB_DQ<26>
J 0
(-615 2510);
DISPLAY 0.659574 (-615 2510);
PAINT MONO (-615 2510);
DISPLAY INVISIBLE (-615 2510);
FORCEPROP 1 LASTPIN (-625 2500) BN 26
J 0
(-637 2508);
DISPLAY 0.680851 (-637 2508);
PAINT GREEN (-637 2508);
FORCEPROP 2 LAST CDS_LIB standard
J 0
(-575 2500);
DISPLAY INVISIBLE (-575 2500);
FORCEPROP 1 LAST BODY_TYPE PLUMBING
J 0
(-575 2550);
DISPLAY 0.872340 (-575 2550);
PAINT GREEN (-575 2550);
DISPLAY INVISIBLE (-575 2550);
FORCEPROP 1 LAST HDL_TAP TRUE
J 0
(-250 2375);
DISPLAY 0.872340 (-250 2375);
DISPLAY INVISIBLE (-250 2375);
FORCEPROP 1 LAST PATH I56
J 0
(-577 2500);
DISPLAY 0.872340 (-577 2500);
PAINT GREEN (-577 2500);
DISPLAY INVISIBLE (-577 2500);
FORCEADD TAP..1
(-575 2300);
FORCEPROP 3 LASTPIN (-625 2300) SIG_NAME M_B_CPU1_SB_DQ<22>
J 0
(-615 2310);
DISPLAY 0.659574 (-615 2310);
PAINT MONO (-615 2310);
DISPLAY INVISIBLE (-615 2310);
FORCEPROP 1 LASTPIN (-625 2300) BN 22
J 0
(-637 2308);
DISPLAY 0.680851 (-637 2308);
PAINT GREEN (-637 2308);
FORCEPROP 2 LAST CDS_LIB standard
J 0
(-575 2300);
DISPLAY INVISIBLE (-575 2300);
FORCEPROP 1 LAST BODY_TYPE PLUMBING
J 0
(-575 2350);
DISPLAY 0.872340 (-575 2350);
PAINT GREEN (-575 2350);
DISPLAY INVISIBLE (-575 2350);
FORCEPROP 1 LAST HDL_TAP TRUE
J 0
(-250 2175);
DISPLAY 0.872340 (-250 2175);
DISPLAY INVISIBLE (-250 2175);
FORCEPROP 1 LAST PATH I57
J 0
(-577 2300);
DISPLAY 0.872340 (-577 2300);
PAINT GREEN (-577 2300);
DISPLAY INVISIBLE (-577 2300);
FORCEADD TAP..1
(-575 2400);
FORCEPROP 3 LASTPIN (-625 2400) SIG_NAME M_B_CPU1_SB_DQ<24>
J 0
(-615 2410);
DISPLAY 0.659574 (-615 2410);
PAINT MONO (-615 2410);
DISPLAY INVISIBLE (-615 2410);
FORCEPROP 1 LASTPIN (-625 2400) BN 24
J 0
(-637 2408);
DISPLAY 0.680851 (-637 2408);
PAINT GREEN (-637 2408);
FORCEPROP 2 LAST CDS_LIB standard
J 0
(-575 2400);
DISPLAY INVISIBLE (-575 2400);
FORCEPROP 1 LAST BODY_TYPE PLUMBING
J 0
(-575 2450);
DISPLAY 0.872340 (-575 2450);
PAINT GREEN (-575 2450);
DISPLAY INVISIBLE (-575 2450);
FORCEPROP 1 LAST HDL_TAP TRUE
J 0
(-250 2275);
DISPLAY 0.872340 (-250 2275);
DISPLAY INVISIBLE (-250 2275);
FORCEPROP 1 LAST PATH I58
J 0
(-577 2400);
DISPLAY 0.872340 (-577 2400);
PAINT GREEN (-577 2400);
DISPLAY INVISIBLE (-577 2400);
FORCEADD TAP..1
(-575 2350);
FORCEPROP 3 LASTPIN (-625 2350) SIG_NAME M_B_CPU1_SB_DQ<23>
J 0
(-615 2360);
DISPLAY 0.659574 (-615 2360);
PAINT MONO (-615 2360);
DISPLAY INVISIBLE (-615 2360);
FORCEPROP 1 LASTPIN (-625 2350) BN 23
J 0
(-637 2358);
DISPLAY 0.680851 (-637 2358);
PAINT GREEN (-637 2358);
FORCEPROP 2 LAST CDS_LIB standard
J 0
(-575 2350);
DISPLAY INVISIBLE (-575 2350);
FORCEPROP 1 LAST BODY_TYPE PLUMBING
J 0
(-575 2400);
DISPLAY 0.872340 (-575 2400);
PAINT GREEN (-575 2400);
DISPLAY INVISIBLE (-575 2400);
FORCEPROP 1 LAST HDL_TAP TRUE
J 0
(-250 2225);
DISPLAY 0.872340 (-250 2225);
DISPLAY INVISIBLE (-250 2225);
FORCEPROP 1 LAST PATH I59
J 0
(-577 2350);
DISPLAY 0.872340 (-577 2350);
PAINT GREEN (-577 2350);
DISPLAY INVISIBLE (-577 2350);
FORCEADD OFFPAGE..3
R 2
(-3150 1550);
FORCEPROP 2 LAST $XR0 114 
J 0
(-3430 1550);
DISPLAY 0.638298 (-3430 1550);
PAINT MONO (-3430 1550);
FORCEPROP 2 LAST CDS_LIB standard
J 0
(-3150 1550);
PAINT MONO (-3150 1550);
DISPLAY INVISIBLE (-3150 1550);
FORCEPROP 1 LAST OFFPAGE TRUE
J 2
(-3475 1425);
DISPLAY 0.872340 (-3475 1425);
DISPLAY INVISIBLE (-3475 1425);
FORCEPROP 1 LAST COMMENT_BODY TRUE
J 2
(-3100 1450);
DISPLAY 0.872340 (-3100 1450);
PAINT GREEN (-3100 1450);
DISPLAY INVISIBLE (-3100 1450);
FORCEPROP 2 LAST PATH I6
J 0
(-3100 1625);
DISPLAY 1.021277 (-3100 1625);
DISPLAY INVISIBLE (-3100 1625);
FORCEADD TAP..1
R 2
(-2225 2550);
FORCEPROP 3 LASTPIN (-2175 2550) SIG_NAME M_B_CPU1_SB_CB<7>
J 0
(-2165 2560);
DISPLAY 0.659574 (-2165 2560);
PAINT MONO (-2165 2560);
DISPLAY INVISIBLE (-2165 2560);
FORCEPROP 1 LASTPIN (-2175 2550) BN 7
J 2
(-2163 2558);
DISPLAY 0.680851 (-2163 2558);
PAINT GREEN (-2163 2558);
FORCEPROP 2 LAST CDS_LIB standard
J 0
(-2225 2550);
DISPLAY INVISIBLE (-2225 2550);
FORCEPROP 1 LAST BODY_TYPE PLUMBING
J 2
(-2225 2600);
DISPLAY 0.872340 (-2225 2600);
PAINT GREEN (-2225 2600);
DISPLAY INVISIBLE (-2225 2600);
FORCEPROP 1 LAST HDL_TAP TRUE
J 2
(-2550 2425);
DISPLAY 0.872340 (-2550 2425);
DISPLAY INVISIBLE (-2550 2425);
FORCEPROP 1 LAST PATH I60
J 2
(-2223 2550);
DISPLAY 0.872340 (-2223 2550);
PAINT GREEN (-2223 2550);
DISPLAY INVISIBLE (-2223 2550);
FORCEADD TAP..1
R 2
(-2225 2650);
FORCEPROP 3 LASTPIN (-2175 2650) SIG_NAME M_B_CPU1_SA_CB<0>
J 0
(-2165 2660);
DISPLAY 0.659574 (-2165 2660);
PAINT MONO (-2165 2660);
DISPLAY INVISIBLE (-2165 2660);
FORCEPROP 1 LASTPIN (-2175 2650) BN 0
J 2
(-2163 2658);
DISPLAY 0.680851 (-2163 2658);
PAINT GREEN (-2163 2658);
FORCEPROP 2 LAST CDS_LIB standard
J 0
(-2225 2650);
PAINT MONO (-2225 2650);
DISPLAY INVISIBLE (-2225 2650);
FORCEPROP 1 LAST BODY_TYPE PLUMBING
J 2
(-2225 2700);
DISPLAY 0.872340 (-2225 2700);
PAINT GREEN (-2225 2700);
DISPLAY INVISIBLE (-2225 2700);
FORCEPROP 1 LAST HDL_TAP TRUE
J 2
(-2550 2525);
DISPLAY 0.872340 (-2550 2525);
DISPLAY INVISIBLE (-2550 2525);
FORCEPROP 1 LAST PATH I61
J 2
(-2223 2650);
DISPLAY 0.872340 (-2223 2650);
PAINT GREEN (-2223 2650);
DISPLAY INVISIBLE (-2223 2650);
FORCEADD TAP..1
R 2
(-2225 2700);
FORCEPROP 3 LASTPIN (-2175 2700) SIG_NAME M_B_CPU1_SA_CB<1>
J 0
(-2165 2710);
DISPLAY 0.659574 (-2165 2710);
PAINT MONO (-2165 2710);
DISPLAY INVISIBLE (-2165 2710);
FORCEPROP 1 LASTPIN (-2175 2700) BN 1
J 2
(-2163 2708);
DISPLAY 0.680851 (-2163 2708);
PAINT GREEN (-2163 2708);
FORCEPROP 2 LAST CDS_LIB standard
J 0
(-2225 2700);
DISPLAY INVISIBLE (-2225 2700);
FORCEPROP 1 LAST BODY_TYPE PLUMBING
J 2
(-2225 2750);
DISPLAY 0.872340 (-2225 2750);
PAINT GREEN (-2225 2750);
DISPLAY INVISIBLE (-2225 2750);
FORCEPROP 1 LAST HDL_TAP TRUE
J 2
(-2550 2575);
DISPLAY 0.872340 (-2550 2575);
DISPLAY INVISIBLE (-2550 2575);
FORCEPROP 1 LAST PATH I62
J 2
(-2223 2700);
DISPLAY 0.872340 (-2223 2700);
PAINT GREEN (-2223 2700);
DISPLAY INVISIBLE (-2223 2700);
FORCEADD TAP..1
R 2
(-2225 2750);
FORCEPROP 3 LASTPIN (-2175 2750) SIG_NAME M_B_CPU1_SA_CB<2>
J 0
(-2165 2760);
DISPLAY 0.659574 (-2165 2760);
PAINT MONO (-2165 2760);
DISPLAY INVISIBLE (-2165 2760);
FORCEPROP 1 LASTPIN (-2175 2750) BN 2
J 2
(-2163 2758);
DISPLAY 0.680851 (-2163 2758);
PAINT GREEN (-2163 2758);
FORCEPROP 2 LAST CDS_LIB standard
J 0
(-2225 2750);
DISPLAY INVISIBLE (-2225 2750);
FORCEPROP 1 LAST BODY_TYPE PLUMBING
J 2
(-2225 2800);
DISPLAY 0.872340 (-2225 2800);
PAINT GREEN (-2225 2800);
DISPLAY INVISIBLE (-2225 2800);
FORCEPROP 1 LAST HDL_TAP TRUE
J 2
(-2550 2625);
DISPLAY 0.872340 (-2550 2625);
DISPLAY INVISIBLE (-2550 2625);
FORCEPROP 1 LAST PATH I63
J 2
(-2223 2750);
DISPLAY 0.872340 (-2223 2750);
PAINT GREEN (-2223 2750);
DISPLAY INVISIBLE (-2223 2750);
FORCEADD TAP..1
R 2
(-2225 2800);
FORCEPROP 3 LASTPIN (-2175 2800) SIG_NAME M_B_CPU1_SA_CB<3>
J 0
(-2165 2810);
DISPLAY 0.659574 (-2165 2810);
PAINT MONO (-2165 2810);
DISPLAY INVISIBLE (-2165 2810);
FORCEPROP 1 LASTPIN (-2175 2800) BN 3
J 2
(-2163 2808);
DISPLAY 0.680851 (-2163 2808);
PAINT GREEN (-2163 2808);
FORCEPROP 2 LAST CDS_LIB standard
J 0
(-2225 2800);
DISPLAY INVISIBLE (-2225 2800);
FORCEPROP 1 LAST BODY_TYPE PLUMBING
J 2
(-2225 2850);
DISPLAY 0.872340 (-2225 2850);
PAINT GREEN (-2225 2850);
DISPLAY INVISIBLE (-2225 2850);
FORCEPROP 1 LAST HDL_TAP TRUE
J 2
(-2550 2675);
DISPLAY 0.872340 (-2550 2675);
DISPLAY INVISIBLE (-2550 2675);
FORCEPROP 1 LAST PATH I64
J 2
(-2223 2800);
DISPLAY 0.872340 (-2223 2800);
PAINT GREEN (-2223 2800);
DISPLAY INVISIBLE (-2223 2800);
FORCEADD TAP..1
R 2
(-2225 2850);
FORCEPROP 3 LASTPIN (-2175 2850) SIG_NAME M_B_CPU1_SA_CB<4>
J 0
(-2165 2860);
DISPLAY 0.659574 (-2165 2860);
PAINT MONO (-2165 2860);
DISPLAY INVISIBLE (-2165 2860);
FORCEPROP 1 LASTPIN (-2175 2850) BN 4
J 2
(-2163 2858);
DISPLAY 0.680851 (-2163 2858);
PAINT GREEN (-2163 2858);
FORCEPROP 2 LAST CDS_LIB standard
J 0
(-2225 2850);
DISPLAY INVISIBLE (-2225 2850);
FORCEPROP 1 LAST BODY_TYPE PLUMBING
J 2
(-2225 2900);
DISPLAY 0.872340 (-2225 2900);
PAINT GREEN (-2225 2900);
DISPLAY INVISIBLE (-2225 2900);
FORCEPROP 1 LAST HDL_TAP TRUE
J 2
(-2550 2725);
DISPLAY 0.872340 (-2550 2725);
DISPLAY INVISIBLE (-2550 2725);
FORCEPROP 1 LAST PATH I65
J 2
(-2223 2850);
DISPLAY 0.872340 (-2223 2850);
PAINT GREEN (-2223 2850);
DISPLAY INVISIBLE (-2223 2850);
FORCEADD TAP..1
R 2
(-2225 2900);
FORCEPROP 3 LASTPIN (-2175 2900) SIG_NAME M_B_CPU1_SA_CB<5>
J 0
(-2165 2910);
DISPLAY 0.659574 (-2165 2910);
PAINT MONO (-2165 2910);
DISPLAY INVISIBLE (-2165 2910);
FORCEPROP 1 LASTPIN (-2175 2900) BN 5
J 2
(-2163 2908);
DISPLAY 0.680851 (-2163 2908);
PAINT GREEN (-2163 2908);
FORCEPROP 2 LAST CDS_LIB standard
J 0
(-2225 2900);
DISPLAY INVISIBLE (-2225 2900);
FORCEPROP 1 LAST BODY_TYPE PLUMBING
J 2
(-2225 2950);
DISPLAY 0.872340 (-2225 2950);
PAINT GREEN (-2225 2950);
DISPLAY INVISIBLE (-2225 2950);
FORCEPROP 1 LAST HDL_TAP TRUE
J 2
(-2550 2775);
DISPLAY 0.872340 (-2550 2775);
DISPLAY INVISIBLE (-2550 2775);
FORCEPROP 1 LAST PATH I66
J 2
(-2223 2900);
DISPLAY 0.872340 (-2223 2900);
PAINT GREEN (-2223 2900);
DISPLAY INVISIBLE (-2223 2900);
FORCEADD TAP..1
R 2
(-2225 3000);
FORCEPROP 3 LASTPIN (-2175 3000) SIG_NAME M_B_CPU1_SA_CB<7>
J 0
(-2165 3010);
DISPLAY 0.659574 (-2165 3010);
PAINT MONO (-2165 3010);
DISPLAY INVISIBLE (-2165 3010);
FORCEPROP 1 LASTPIN (-2175 3000) BN 7
J 2
(-2163 3008);
DISPLAY 0.680851 (-2163 3008);
PAINT GREEN (-2163 3008);
FORCEPROP 2 LAST CDS_LIB standard
J 0
(-2225 3000);
DISPLAY INVISIBLE (-2225 3000);
FORCEPROP 1 LAST BODY_TYPE PLUMBING
J 2
(-2225 3050);
DISPLAY 0.872340 (-2225 3050);
PAINT GREEN (-2225 3050);
DISPLAY INVISIBLE (-2225 3050);
FORCEPROP 1 LAST HDL_TAP TRUE
J 2
(-2550 2875);
DISPLAY 0.872340 (-2550 2875);
DISPLAY INVISIBLE (-2550 2875);
FORCEPROP 1 LAST PATH I67
J 2
(-2223 3000);
DISPLAY 0.872340 (-2223 3000);
PAINT GREEN (-2223 3000);
DISPLAY INVISIBLE (-2223 3000);
FORCEADD TAP..1
R 2
(-2225 2950);
FORCEPROP 3 LASTPIN (-2175 2950) SIG_NAME M_B_CPU1_SA_CB<6>
J 0
(-2165 2960);
DISPLAY 0.659574 (-2165 2960);
PAINT MONO (-2165 2960);
DISPLAY INVISIBLE (-2165 2960);
FORCEPROP 1 LASTPIN (-2175 2950) BN 6
J 2
(-2163 2958);
DISPLAY 0.680851 (-2163 2958);
PAINT GREEN (-2163 2958);
FORCEPROP 2 LAST CDS_LIB standard
J 0
(-2225 2950);
DISPLAY INVISIBLE (-2225 2950);
FORCEPROP 1 LAST BODY_TYPE PLUMBING
J 2
(-2225 3000);
DISPLAY 0.872340 (-2225 3000);
PAINT GREEN (-2225 3000);
DISPLAY INVISIBLE (-2225 3000);
FORCEPROP 1 LAST HDL_TAP TRUE
J 2
(-2550 2825);
DISPLAY 0.872340 (-2550 2825);
DISPLAY INVISIBLE (-2550 2825);
FORCEPROP 1 LAST PATH I68
J 2
(-2223 2950);
DISPLAY 0.872340 (-2223 2950);
PAINT GREEN (-2223 2950);
DISPLAY INVISIBLE (-2223 2950);
FORCEADD TAP..1
R 2
(-2225 3800);
FORCEPROP 3 LASTPIN (-2175 3800) SIG_NAME M_B_CPU1_SB_CA<2>
J 0
(-2165 3810);
DISPLAY 0.659574 (-2165 3810);
PAINT MONO (-2165 3810);
DISPLAY INVISIBLE (-2165 3810);
FORCEPROP 1 LASTPIN (-2175 3800) BN 2
J 2
(-2163 3808);
DISPLAY 0.680851 (-2163 3808);
PAINT GREEN (-2163 3808);
FORCEPROP 2 LAST CDS_LIB standard
J 0
(-2225 3800);
DISPLAY INVISIBLE (-2225 3800);
FORCEPROP 1 LAST BODY_TYPE PLUMBING
J 2
(-2225 3850);
DISPLAY 0.872340 (-2225 3850);
PAINT GREEN (-2225 3850);
DISPLAY INVISIBLE (-2225 3850);
FORCEPROP 1 LAST HDL_TAP TRUE
J 2
(-2550 3675);
DISPLAY 0.872340 (-2550 3675);
DISPLAY INVISIBLE (-2550 3675);
FORCEPROP 1 LAST PATH I69
J 2
(-2223 3800);
DISPLAY 0.872340 (-2223 3800);
PAINT GREEN (-2223 3800);
DISPLAY INVISIBLE (-2223 3800);
FORCEADD TAP..1
R 2
(-2225 3750);
FORCEPROP 3 LASTPIN (-2175 3750) SIG_NAME M_B_CPU1_SB_CA<1>
J 0
(-2165 3760);
DISPLAY 0.659574 (-2165 3760);
PAINT MONO (-2165 3760);
DISPLAY INVISIBLE (-2165 3760);
FORCEPROP 1 LASTPIN (-2175 3750) BN 1
J 2
(-2163 3758);
DISPLAY 0.680851 (-2163 3758);
PAINT GREEN (-2163 3758);
FORCEPROP 2 LAST CDS_LIB standard
J 0
(-2225 3750);
DISPLAY INVISIBLE (-2225 3750);
FORCEPROP 1 LAST BODY_TYPE PLUMBING
J 2
(-2225 3800);
DISPLAY 0.872340 (-2225 3800);
PAINT GREEN (-2225 3800);
DISPLAY INVISIBLE (-2225 3800);
FORCEPROP 1 LAST HDL_TAP TRUE
J 2
(-2550 3625);
DISPLAY 0.872340 (-2550 3625);
DISPLAY INVISIBLE (-2550 3625);
FORCEPROP 1 LAST PATH I70
J 2
(-2223 3750);
DISPLAY 0.872340 (-2223 3750);
PAINT GREEN (-2223 3750);
DISPLAY INVISIBLE (-2223 3750);
FORCEADD TAP..1
R 2
(-2225 3700);
FORCEPROP 3 LASTPIN (-2175 3700) SIG_NAME M_B_CPU1_SB_CA<0>
J 0
(-2165 3710);
DISPLAY 0.659574 (-2165 3710);
PAINT MONO (-2165 3710);
DISPLAY INVISIBLE (-2165 3710);
FORCEPROP 1 LASTPIN (-2175 3700) BN 0
J 2
(-2163 3708);
DISPLAY 0.680851 (-2163 3708);
PAINT GREEN (-2163 3708);
FORCEPROP 2 LAST CDS_LIB standard
J 0
(-2225 3700);
DISPLAY INVISIBLE (-2225 3700);
FORCEPROP 1 LAST BODY_TYPE PLUMBING
J 2
(-2225 3750);
DISPLAY 0.872340 (-2225 3750);
PAINT GREEN (-2225 3750);
DISPLAY INVISIBLE (-2225 3750);
FORCEPROP 1 LAST HDL_TAP TRUE
J 2
(-2550 3575);
DISPLAY 0.872340 (-2550 3575);
DISPLAY INVISIBLE (-2550 3575);
FORCEPROP 1 LAST PATH I71
J 2
(-2223 3700);
DISPLAY 0.872340 (-2223 3700);
PAINT GREEN (-2223 3700);
DISPLAY INVISIBLE (-2223 3700);
FORCEADD TAP..1
R 2
(-2225 3900);
FORCEPROP 3 LASTPIN (-2175 3900) SIG_NAME M_B_CPU1_SB_CA<4>
J 0
(-2165 3910);
DISPLAY 0.659574 (-2165 3910);
PAINT MONO (-2165 3910);
DISPLAY INVISIBLE (-2165 3910);
FORCEPROP 1 LASTPIN (-2175 3900) BN 4
J 2
(-2163 3908);
DISPLAY 0.680851 (-2163 3908);
PAINT GREEN (-2163 3908);
FORCEPROP 2 LAST CDS_LIB standard
J 0
(-2225 3900);
DISPLAY INVISIBLE (-2225 3900);
FORCEPROP 1 LAST BODY_TYPE PLUMBING
J 2
(-2225 3950);
DISPLAY 0.872340 (-2225 3950);
PAINT GREEN (-2225 3950);
DISPLAY INVISIBLE (-2225 3950);
FORCEPROP 1 LAST HDL_TAP TRUE
J 2
(-2550 3775);
DISPLAY 0.872340 (-2550 3775);
DISPLAY INVISIBLE (-2550 3775);
FORCEPROP 1 LAST PATH I72
J 2
(-2223 3900);
DISPLAY 0.872340 (-2223 3900);
PAINT GREEN (-2223 3900);
DISPLAY INVISIBLE (-2223 3900);
FORCEADD TAP..1
R 2
(-2225 3850);
FORCEPROP 3 LASTPIN (-2175 3850) SIG_NAME M_B_CPU1_SB_CA<3>
J 0
(-2165 3860);
DISPLAY 0.659574 (-2165 3860);
PAINT MONO (-2165 3860);
DISPLAY INVISIBLE (-2165 3860);
FORCEPROP 1 LASTPIN (-2175 3850) BN 3
J 2
(-2163 3858);
DISPLAY 0.680851 (-2163 3858);
PAINT GREEN (-2163 3858);
FORCEPROP 2 LAST CDS_LIB standard
J 0
(-2225 3850);
DISPLAY INVISIBLE (-2225 3850);
FORCEPROP 1 LAST BODY_TYPE PLUMBING
J 2
(-2225 3900);
DISPLAY 0.872340 (-2225 3900);
PAINT GREEN (-2225 3900);
DISPLAY INVISIBLE (-2225 3900);
FORCEPROP 1 LAST HDL_TAP TRUE
J 2
(-2550 3725);
DISPLAY 0.872340 (-2550 3725);
DISPLAY INVISIBLE (-2550 3725);
FORCEPROP 1 LAST PATH I73
J 2
(-2223 3850);
DISPLAY 0.872340 (-2223 3850);
PAINT GREEN (-2223 3850);
DISPLAY INVISIBLE (-2223 3850);
FORCEADD TAP..1
R 2
(-2225 3950);
FORCEPROP 3 LASTPIN (-2175 3950) SIG_NAME M_B_CPU1_SB_CA<5>
J 0
(-2165 3960);
DISPLAY 0.659574 (-2165 3960);
PAINT MONO (-2165 3960);
DISPLAY INVISIBLE (-2165 3960);
FORCEPROP 1 LASTPIN (-2175 3950) BN 5
J 2
(-2163 3958);
DISPLAY 0.680851 (-2163 3958);
PAINT GREEN (-2163 3958);
FORCEPROP 2 LAST CDS_LIB standard
J 0
(-2225 3950);
DISPLAY INVISIBLE (-2225 3950);
FORCEPROP 1 LAST BODY_TYPE PLUMBING
J 2
(-2225 4000);
DISPLAY 0.872340 (-2225 4000);
PAINT GREEN (-2225 4000);
DISPLAY INVISIBLE (-2225 4000);
FORCEPROP 1 LAST HDL_TAP TRUE
J 2
(-2550 3825);
DISPLAY 0.872340 (-2550 3825);
DISPLAY INVISIBLE (-2550 3825);
FORCEPROP 1 LAST PATH I74
J 2
(-2223 3950);
DISPLAY 0.872340 (-2223 3950);
PAINT GREEN (-2223 3950);
DISPLAY INVISIBLE (-2223 3950);
FORCEADD TAP..1
R 2
(-2225 4000);
FORCEPROP 3 LASTPIN (-2175 4000) SIG_NAME M_B_CPU1_SB_CA<6>
J 0
(-2165 4010);
DISPLAY 0.659574 (-2165 4010);
PAINT MONO (-2165 4010);
DISPLAY INVISIBLE (-2165 4010);
FORCEPROP 1 LASTPIN (-2175 4000) BN 6
J 2
(-2163 4008);
DISPLAY 0.680851 (-2163 4008);
PAINT GREEN (-2163 4008);
FORCEPROP 2 LAST CDS_LIB standard
J 0
(-2225 4000);
DISPLAY INVISIBLE (-2225 4000);
FORCEPROP 1 LAST BODY_TYPE PLUMBING
J 2
(-2225 4050);
DISPLAY 0.872340 (-2225 4050);
PAINT GREEN (-2225 4050);
DISPLAY INVISIBLE (-2225 4050);
FORCEPROP 1 LAST HDL_TAP TRUE
J 2
(-2550 3875);
DISPLAY 0.872340 (-2550 3875);
DISPLAY INVISIBLE (-2550 3875);
FORCEPROP 1 LAST PATH I75
J 2
(-2223 4000);
DISPLAY 0.872340 (-2223 4000);
PAINT GREEN (-2223 4000);
DISPLAY INVISIBLE (-2223 4000);
FORCEADD TAP..1
R 2
(-2225 4100);
FORCEPROP 3 LASTPIN (-2175 4100) SIG_NAME M_B_CPU1_SA_CA<0>
J 0
(-2165 4110);
DISPLAY 0.659574 (-2165 4110);
PAINT MONO (-2165 4110);
DISPLAY INVISIBLE (-2165 4110);
FORCEPROP 1 LASTPIN (-2175 4100) BN 0
J 2
(-2163 4108);
DISPLAY 0.680851 (-2163 4108);
PAINT GREEN (-2163 4108);
FORCEPROP 2 LAST CDS_LIB standard
J 0
(-2225 4100);
DISPLAY INVISIBLE (-2225 4100);
FORCEPROP 1 LAST BODY_TYPE PLUMBING
J 2
(-2225 4150);
DISPLAY 0.872340 (-2225 4150);
PAINT GREEN (-2225 4150);
DISPLAY INVISIBLE (-2225 4150);
FORCEPROP 1 LAST HDL_TAP TRUE
J 2
(-2550 3975);
DISPLAY 0.872340 (-2550 3975);
DISPLAY INVISIBLE (-2550 3975);
FORCEPROP 1 LAST PATH I76
J 2
(-2223 4100);
DISPLAY 0.872340 (-2223 4100);
PAINT GREEN (-2223 4100);
DISPLAY INVISIBLE (-2223 4100);
FORCEADD TAP..1
R 2
(-2225 4150);
FORCEPROP 3 LASTPIN (-2175 4150) SIG_NAME M_B_CPU1_SA_CA<1>
J 0
(-2165 4160);
DISPLAY 0.659574 (-2165 4160);
PAINT MONO (-2165 4160);
DISPLAY INVISIBLE (-2165 4160);
FORCEPROP 1 LASTPIN (-2175 4150) BN 1
J 2
(-2163 4158);
DISPLAY 0.680851 (-2163 4158);
PAINT GREEN (-2163 4158);
FORCEPROP 2 LAST CDS_LIB standard
J 0
(-2225 4150);
DISPLAY INVISIBLE (-2225 4150);
FORCEPROP 1 LAST BODY_TYPE PLUMBING
J 2
(-2225 4200);
DISPLAY 0.872340 (-2225 4200);
PAINT GREEN (-2225 4200);
DISPLAY INVISIBLE (-2225 4200);
FORCEPROP 1 LAST HDL_TAP TRUE
J 2
(-2550 4025);
DISPLAY 0.872340 (-2550 4025);
DISPLAY INVISIBLE (-2550 4025);
FORCEPROP 1 LAST PATH I77
J 2
(-2223 4150);
DISPLAY 0.872340 (-2223 4150);
PAINT GREEN (-2223 4150);
DISPLAY INVISIBLE (-2223 4150);
FORCEADD TAP..1
R 2
(-2225 4200);
FORCEPROP 3 LASTPIN (-2175 4200) SIG_NAME M_B_CPU1_SA_CA<2>
J 0
(-2165 4210);
DISPLAY 0.659574 (-2165 4210);
PAINT MONO (-2165 4210);
DISPLAY INVISIBLE (-2165 4210);
FORCEPROP 1 LASTPIN (-2175 4200) BN 2
J 2
(-2163 4208);
DISPLAY 0.680851 (-2163 4208);
PAINT GREEN (-2163 4208);
FORCEPROP 2 LAST CDS_LIB standard
J 0
(-2225 4200);
DISPLAY INVISIBLE (-2225 4200);
FORCEPROP 1 LAST BODY_TYPE PLUMBING
J 2
(-2225 4250);
DISPLAY 0.872340 (-2225 4250);
PAINT GREEN (-2225 4250);
DISPLAY INVISIBLE (-2225 4250);
FORCEPROP 1 LAST HDL_TAP TRUE
J 2
(-2550 4075);
DISPLAY 0.872340 (-2550 4075);
DISPLAY INVISIBLE (-2550 4075);
FORCEPROP 1 LAST PATH I78
J 2
(-2223 4200);
DISPLAY 0.872340 (-2223 4200);
PAINT GREEN (-2223 4200);
DISPLAY INVISIBLE (-2223 4200);
FORCEADD TAP..1
R 2
(-2225 4250);
FORCEPROP 3 LASTPIN (-2175 4250) SIG_NAME M_B_CPU1_SA_CA<3>
J 0
(-2165 4260);
DISPLAY 0.659574 (-2165 4260);
PAINT MONO (-2165 4260);
DISPLAY INVISIBLE (-2165 4260);
FORCEPROP 1 LASTPIN (-2175 4250) BN 3
J 2
(-2163 4258);
DISPLAY 0.680851 (-2163 4258);
PAINT GREEN (-2163 4258);
FORCEPROP 2 LAST CDS_LIB standard
J 0
(-2225 4250);
DISPLAY INVISIBLE (-2225 4250);
FORCEPROP 1 LAST BODY_TYPE PLUMBING
J 2
(-2225 4300);
DISPLAY 0.872340 (-2225 4300);
PAINT GREEN (-2225 4300);
DISPLAY INVISIBLE (-2225 4300);
FORCEPROP 1 LAST HDL_TAP TRUE
J 2
(-2550 4125);
DISPLAY 0.872340 (-2550 4125);
DISPLAY INVISIBLE (-2550 4125);
FORCEPROP 1 LAST PATH I79
J 2
(-2223 4250);
DISPLAY 0.872340 (-2223 4250);
PAINT GREEN (-2223 4250);
DISPLAY INVISIBLE (-2223 4250);
FORCEADD OFFPAGE..1
(-3075 1850);
FORCEPROP 2 LAST $XR7 105 
J 0
(-3567 1886);
DISPLAY 0.638298 (-3567 1886);
PAINT MONO (-3567 1886);
FORCEPROP 2 LAST $XR6 104 
J 0
(-3447 1886);
DISPLAY 0.638298 (-3447 1886);
PAINT MONO (-3447 1886);
FORCEPROP 2 LAST $XR5 103 
J 0
(-3597 1814);
DISPLAY 0.638298 (-3597 1814);
PAINT MONO (-3597 1814);
FORCEPROP 2 LAST $XR4 102 
J 0
(-3477 1814);
DISPLAY 0.638298 (-3477 1814);
PAINT MONO (-3477 1814);
FORCEPROP 2 LAST $XR3 101 
J 0
(-3357 1814);
DISPLAY 0.638298 (-3357 1814);
PAINT MONO (-3357 1814);
FORCEPROP 2 LAST $XR2 99 
J 0
(-3537 1850);
DISPLAY 0.638298 (-3537 1850);
PAINT MONO (-3537 1850);
FORCEPROP 2 LAST $XR1 98 
J 0
(-3447 1850);
DISPLAY 0.638298 (-3447 1850);
PAINT MONO (-3447 1850);
FORCEPROP 2 LAST $XR0 230 
J 0
(-3357 1850);
DISPLAY 0.638298 (-3357 1850);
PAINT MONO (-3357 1850);
FORCEPROP 2 LAST CDS_LIB standard
J 0
(-3075 1850);
PAINT MONO (-3075 1850);
DISPLAY INVISIBLE (-3075 1850);
FORCEPROP 1 LAST OFFPAGE TRUE
J 0
(-2750 1725);
DISPLAY 0.872340 (-2750 1725);
DISPLAY INVISIBLE (-2750 1725);
FORCEPROP 1 LAST COMMENT_BODY TRUE
J 0
(-2950 1750);
DISPLAY 0.872340 (-2950 1750);
PAINT GREEN (-2950 1750);
DISPLAY INVISIBLE (-2950 1750);
FORCEPROP 2 LAST PATH I8
J 0
(-3025 1925);
DISPLAY 1.021277 (-3025 1925);
DISPLAY INVISIBLE (-3025 1925);
FORCEADD TAP..1
R 2
(-2225 4300);
FORCEPROP 3 LASTPIN (-2175 4300) SIG_NAME M_B_CPU1_SA_CA<4>
J 0
(-2165 4310);
DISPLAY 0.659574 (-2165 4310);
PAINT MONO (-2165 4310);
DISPLAY INVISIBLE (-2165 4310);
FORCEPROP 1 LASTPIN (-2175 4300) BN 4
J 2
(-2163 4308);
DISPLAY 0.680851 (-2163 4308);
PAINT GREEN (-2163 4308);
FORCEPROP 2 LAST CDS_LIB standard
J 0
(-2225 4300);
DISPLAY INVISIBLE (-2225 4300);
FORCEPROP 1 LAST BODY_TYPE PLUMBING
J 2
(-2225 4350);
DISPLAY 0.872340 (-2225 4350);
PAINT GREEN (-2225 4350);
DISPLAY INVISIBLE (-2225 4350);
FORCEPROP 1 LAST HDL_TAP TRUE
J 2
(-2550 4175);
DISPLAY 0.872340 (-2550 4175);
DISPLAY INVISIBLE (-2550 4175);
FORCEPROP 1 LAST PATH I80
J 2
(-2223 4300);
DISPLAY 0.872340 (-2223 4300);
PAINT GREEN (-2223 4300);
DISPLAY INVISIBLE (-2223 4300);
FORCEADD TAP..1
R 2
(-2225 4400);
FORCEPROP 3 LASTPIN (-2175 4400) SIG_NAME M_B_CPU1_SA_CA<6>
J 0
(-2165 4410);
DISPLAY 0.659574 (-2165 4410);
PAINT MONO (-2165 4410);
DISPLAY INVISIBLE (-2165 4410);
FORCEPROP 1 LASTPIN (-2175 4400) BN 6
J 2
(-2163 4408);
DISPLAY 0.680851 (-2163 4408);
PAINT GREEN (-2163 4408);
FORCEPROP 2 LAST CDS_LIB standard
J 0
(-2225 4400);
DISPLAY INVISIBLE (-2225 4400);
FORCEPROP 1 LAST BODY_TYPE PLUMBING
J 2
(-2225 4450);
DISPLAY 0.872340 (-2225 4450);
PAINT GREEN (-2225 4450);
DISPLAY INVISIBLE (-2225 4450);
FORCEPROP 1 LAST HDL_TAP TRUE
J 2
(-2550 4275);
DISPLAY 0.872340 (-2550 4275);
DISPLAY INVISIBLE (-2550 4275);
FORCEPROP 1 LAST PATH I81
J 2
(-2223 4400);
DISPLAY 0.872340 (-2223 4400);
PAINT GREEN (-2223 4400);
DISPLAY INVISIBLE (-2223 4400);
FORCEADD TAP..1
R 2
(-2225 4350);
FORCEPROP 3 LASTPIN (-2175 4350) SIG_NAME M_B_CPU1_SA_CA<5>
J 0
(-2165 4360);
DISPLAY 0.659574 (-2165 4360);
PAINT MONO (-2165 4360);
DISPLAY INVISIBLE (-2165 4360);
FORCEPROP 1 LASTPIN (-2175 4350) BN 5
J 2
(-2163 4358);
DISPLAY 0.680851 (-2163 4358);
PAINT GREEN (-2163 4358);
FORCEPROP 2 LAST CDS_LIB standard
J 0
(-2225 4350);
DISPLAY INVISIBLE (-2225 4350);
FORCEPROP 1 LAST BODY_TYPE PLUMBING
J 2
(-2225 4400);
DISPLAY 0.872340 (-2225 4400);
PAINT GREEN (-2225 4400);
DISPLAY INVISIBLE (-2225 4400);
FORCEPROP 1 LAST HDL_TAP TRUE
J 2
(-2550 4225);
DISPLAY 0.872340 (-2550 4225);
DISPLAY INVISIBLE (-2550 4225);
FORCEPROP 1 LAST PATH I82
J 2
(-2223 4350);
DISPLAY 0.872340 (-2223 4350);
PAINT GREEN (-2223 4350);
DISPLAY INVISIBLE (-2223 4350);
FORCEADD TAP..1
(-575 2750);
FORCEPROP 3 LASTPIN (-625 2750) SIG_NAME M_B_CPU1_SB_DQ<31>
J 0
(-615 2760);
DISPLAY 0.659574 (-615 2760);
PAINT MONO (-615 2760);
DISPLAY INVISIBLE (-615 2760);
FORCEPROP 1 LASTPIN (-625 2750) BN 31
J 0
(-637 2758);
DISPLAY 0.680851 (-637 2758);
PAINT GREEN (-637 2758);
FORCEPROP 2 LAST CDS_LIB standard
J 0
(-575 2750);
DISPLAY INVISIBLE (-575 2750);
FORCEPROP 1 LAST BODY_TYPE PLUMBING
J 0
(-575 2800);
DISPLAY 0.872340 (-575 2800);
PAINT GREEN (-575 2800);
DISPLAY INVISIBLE (-575 2800);
FORCEPROP 1 LAST HDL_TAP TRUE
J 0
(-250 2625);
DISPLAY 0.872340 (-250 2625);
DISPLAY INVISIBLE (-250 2625);
FORCEPROP 1 LAST PATH I83
J 0
(-577 2750);
DISPLAY 0.872340 (-577 2750);
PAINT GREEN (-577 2750);
DISPLAY INVISIBLE (-577 2750);
FORCEADD TAP..1
(-575 2700);
FORCEPROP 3 LASTPIN (-625 2700) SIG_NAME M_B_CPU1_SB_DQ<30>
J 0
(-615 2710);
DISPLAY 0.659574 (-615 2710);
PAINT MONO (-615 2710);
DISPLAY INVISIBLE (-615 2710);
FORCEPROP 1 LASTPIN (-625 2700) BN 30
J 0
(-637 2708);
DISPLAY 0.680851 (-637 2708);
PAINT GREEN (-637 2708);
FORCEPROP 2 LAST CDS_LIB standard
J 0
(-575 2700);
DISPLAY INVISIBLE (-575 2700);
FORCEPROP 1 LAST BODY_TYPE PLUMBING
J 0
(-575 2750);
DISPLAY 0.872340 (-575 2750);
PAINT GREEN (-575 2750);
DISPLAY INVISIBLE (-575 2750);
FORCEPROP 1 LAST HDL_TAP TRUE
J 0
(-250 2575);
DISPLAY 0.872340 (-250 2575);
DISPLAY INVISIBLE (-250 2575);
FORCEPROP 1 LAST PATH I84
J 0
(-577 2700);
DISPLAY 0.872340 (-577 2700);
PAINT GREEN (-577 2700);
DISPLAY INVISIBLE (-577 2700);
FORCEADD TAP..1
(-575 2650);
FORCEPROP 3 LASTPIN (-625 2650) SIG_NAME M_B_CPU1_SB_DQ<29>
J 0
(-615 2660);
DISPLAY 0.659574 (-615 2660);
PAINT MONO (-615 2660);
DISPLAY INVISIBLE (-615 2660);
FORCEPROP 1 LASTPIN (-625 2650) BN 29
J 0
(-637 2658);
DISPLAY 0.680851 (-637 2658);
PAINT GREEN (-637 2658);
FORCEPROP 2 LAST CDS_LIB standard
J 0
(-575 2650);
DISPLAY INVISIBLE (-575 2650);
FORCEPROP 1 LAST BODY_TYPE PLUMBING
J 0
(-575 2700);
DISPLAY 0.872340 (-575 2700);
PAINT GREEN (-575 2700);
DISPLAY INVISIBLE (-575 2700);
FORCEPROP 1 LAST HDL_TAP TRUE
J 0
(-250 2525);
DISPLAY 0.872340 (-250 2525);
DISPLAY INVISIBLE (-250 2525);
FORCEPROP 1 LAST PATH I85
J 0
(-577 2650);
DISPLAY 0.872340 (-577 2650);
PAINT GREEN (-577 2650);
DISPLAY INVISIBLE (-577 2650);
FORCEADD TAP..1
(-575 2600);
FORCEPROP 3 LASTPIN (-625 2600) SIG_NAME M_B_CPU1_SB_DQ<28>
J 0
(-615 2610);
DISPLAY 0.659574 (-615 2610);
PAINT MONO (-615 2610);
DISPLAY INVISIBLE (-615 2610);
FORCEPROP 1 LASTPIN (-625 2600) BN 28
J 0
(-637 2608);
DISPLAY 0.680851 (-637 2608);
PAINT GREEN (-637 2608);
FORCEPROP 2 LAST CDS_LIB standard
J 0
(-575 2600);
DISPLAY INVISIBLE (-575 2600);
FORCEPROP 1 LAST BODY_TYPE PLUMBING
J 0
(-575 2650);
DISPLAY 0.872340 (-575 2650);
PAINT GREEN (-575 2650);
DISPLAY INVISIBLE (-575 2650);
FORCEPROP 1 LAST HDL_TAP TRUE
J 0
(-250 2475);
DISPLAY 0.872340 (-250 2475);
DISPLAY INVISIBLE (-250 2475);
FORCEPROP 1 LAST PATH I86
J 0
(-577 2600);
DISPLAY 0.872340 (-577 2600);
PAINT GREEN (-577 2600);
DISPLAY INVISIBLE (-577 2600);
FORCEADD TAP..1
(-575 2550);
FORCEPROP 3 LASTPIN (-625 2550) SIG_NAME M_B_CPU1_SB_DQ<27>
J 0
(-615 2560);
DISPLAY 0.659574 (-615 2560);
PAINT MONO (-615 2560);
DISPLAY INVISIBLE (-615 2560);
FORCEPROP 1 LASTPIN (-625 2550) BN 27
J 0
(-637 2558);
DISPLAY 0.680851 (-637 2558);
PAINT GREEN (-637 2558);
FORCEPROP 2 LAST CDS_LIB standard
J 0
(-575 2550);
DISPLAY INVISIBLE (-575 2550);
FORCEPROP 1 LAST BODY_TYPE PLUMBING
J 0
(-575 2600);
DISPLAY 0.872340 (-575 2600);
PAINT GREEN (-575 2600);
DISPLAY INVISIBLE (-575 2600);
FORCEPROP 1 LAST HDL_TAP TRUE
J 0
(-250 2425);
DISPLAY 0.872340 (-250 2425);
DISPLAY INVISIBLE (-250 2425);
FORCEPROP 1 LAST PATH I87
J 0
(-577 2550);
DISPLAY 0.872340 (-577 2550);
PAINT GREEN (-577 2550);
DISPLAY INVISIBLE (-577 2550);
FORCEADD TAP..1
(-575 2850);
FORCEPROP 3 LASTPIN (-625 2850) SIG_NAME M_B_CPU1_SA_DQ<0>
J 0
(-615 2860);
DISPLAY 0.659574 (-615 2860);
PAINT MONO (-615 2860);
DISPLAY INVISIBLE (-615 2860);
FORCEPROP 1 LASTPIN (-625 2850) BN 0
J 0
(-637 2858);
DISPLAY 0.680851 (-637 2858);
PAINT GREEN (-637 2858);
FORCEPROP 2 LAST CDS_LIB standard
J 0
(-575 2850);
PAINT MONO (-575 2850);
DISPLAY INVISIBLE (-575 2850);
FORCEPROP 1 LAST BODY_TYPE PLUMBING
J 0
(-575 2900);
DISPLAY 0.872340 (-575 2900);
PAINT GREEN (-575 2900);
DISPLAY INVISIBLE (-575 2900);
FORCEPROP 1 LAST HDL_TAP TRUE
J 0
(-250 2725);
DISPLAY 0.872340 (-250 2725);
DISPLAY INVISIBLE (-250 2725);
FORCEPROP 1 LAST PATH I88
J 0
(-577 2850);
DISPLAY 0.872340 (-577 2850);
PAINT GREEN (-577 2850);
DISPLAY INVISIBLE (-577 2850);
FORCEADD TAP..1
(-575 2900);
FORCEPROP 3 LASTPIN (-625 2900) SIG_NAME M_B_CPU1_SA_DQ<1>
J 0
(-615 2910);
DISPLAY 0.659574 (-615 2910);
PAINT MONO (-615 2910);
DISPLAY INVISIBLE (-615 2910);
FORCEPROP 1 LASTPIN (-625 2900) BN 1
J 0
(-637 2908);
DISPLAY 0.680851 (-637 2908);
PAINT GREEN (-637 2908);
FORCEPROP 2 LAST CDS_LIB standard
J 0
(-575 2900);
PAINT MONO (-575 2900);
DISPLAY INVISIBLE (-575 2900);
FORCEPROP 1 LAST BODY_TYPE PLUMBING
J 0
(-575 2950);
DISPLAY 0.872340 (-575 2950);
PAINT GREEN (-575 2950);
DISPLAY INVISIBLE (-575 2950);
FORCEPROP 1 LAST HDL_TAP TRUE
J 0
(-250 2775);
DISPLAY 0.872340 (-250 2775);
DISPLAY INVISIBLE (-250 2775);
FORCEPROP 1 LAST PATH I89
J 0
(-577 2900);
DISPLAY 0.872340 (-577 2900);
PAINT GREEN (-577 2900);
DISPLAY INVISIBLE (-577 2900);
FORCEADD OFFPAGE..1
(-3075 1900);
FORCEPROP 2 LAST $XR0 100 
J 0
(-3357 1900);
DISPLAY 0.638298 (-3357 1900);
PAINT MONO (-3357 1900);
FORCEPROP 2 LAST CDS_LIB standard
J 0
(-3075 1900);
PAINT MONO (-3075 1900);
DISPLAY INVISIBLE (-3075 1900);
FORCEPROP 1 LAST OFFPAGE TRUE
J 0
(-2750 1775);
DISPLAY 0.872340 (-2750 1775);
DISPLAY INVISIBLE (-2750 1775);
FORCEPROP 1 LAST COMMENT_BODY TRUE
J 0
(-2950 1800);
DISPLAY 0.872340 (-2950 1800);
PAINT GREEN (-2950 1800);
DISPLAY INVISIBLE (-2950 1800);
FORCEPROP 2 LAST PATH I9
J 0
(-3025 1975);
DISPLAY 1.021277 (-3025 1975);
DISPLAY INVISIBLE (-3025 1975);
FORCEADD TAP..1
(-575 3000);
FORCEPROP 3 LASTPIN (-625 3000) SIG_NAME M_B_CPU1_SA_DQ<3>
J 0
(-615 3010);
DISPLAY 0.659574 (-615 3010);
PAINT MONO (-615 3010);
DISPLAY INVISIBLE (-615 3010);
FORCEPROP 1 LASTPIN (-625 3000) BN 3
J 0
(-637 3008);
DISPLAY 0.680851 (-637 3008);
PAINT GREEN (-637 3008);
FORCEPROP 2 LAST CDS_LIB standard
J 0
(-575 3000);
PAINT MONO (-575 3000);
DISPLAY INVISIBLE (-575 3000);
FORCEPROP 1 LAST BODY_TYPE PLUMBING
J 0
(-575 3050);
DISPLAY 0.872340 (-575 3050);
PAINT GREEN (-575 3050);
DISPLAY INVISIBLE (-575 3050);
FORCEPROP 1 LAST HDL_TAP TRUE
J 0
(-250 2875);
DISPLAY 0.872340 (-250 2875);
DISPLAY INVISIBLE (-250 2875);
FORCEPROP 1 LAST PATH I90
J 0
(-577 3000);
DISPLAY 0.872340 (-577 3000);
PAINT GREEN (-577 3000);
DISPLAY INVISIBLE (-577 3000);
FORCEADD TAP..1
(-575 3050);
FORCEPROP 3 LASTPIN (-625 3050) SIG_NAME M_B_CPU1_SA_DQ<4>
J 0
(-615 3060);
DISPLAY 0.659574 (-615 3060);
PAINT MONO (-615 3060);
DISPLAY INVISIBLE (-615 3060);
FORCEPROP 1 LASTPIN (-625 3050) BN 4
J 0
(-637 3058);
DISPLAY 0.680851 (-637 3058);
PAINT GREEN (-637 3058);
FORCEPROP 2 LAST CDS_LIB standard
J 0
(-575 3050);
PAINT MONO (-575 3050);
DISPLAY INVISIBLE (-575 3050);
FORCEPROP 1 LAST BODY_TYPE PLUMBING
J 0
(-575 3100);
DISPLAY 0.872340 (-575 3100);
PAINT GREEN (-575 3100);
DISPLAY INVISIBLE (-575 3100);
FORCEPROP 1 LAST HDL_TAP TRUE
J 0
(-250 2925);
DISPLAY 0.872340 (-250 2925);
DISPLAY INVISIBLE (-250 2925);
FORCEPROP 1 LAST PATH I91
J 0
(-577 3050);
DISPLAY 0.872340 (-577 3050);
PAINT GREEN (-577 3050);
DISPLAY INVISIBLE (-577 3050);
FORCEADD TAP..1
(-575 2950);
FORCEPROP 3 LASTPIN (-625 2950) SIG_NAME M_B_CPU1_SA_DQ<2>
J 0
(-615 2960);
DISPLAY 0.659574 (-615 2960);
PAINT MONO (-615 2960);
DISPLAY INVISIBLE (-615 2960);
FORCEPROP 1 LASTPIN (-625 2950) BN 2
J 0
(-637 2958);
DISPLAY 0.680851 (-637 2958);
PAINT GREEN (-637 2958);
FORCEPROP 2 LAST CDS_LIB standard
J 0
(-575 2950);
PAINT MONO (-575 2950);
DISPLAY INVISIBLE (-575 2950);
FORCEPROP 1 LAST BODY_TYPE PLUMBING
J 0
(-575 3000);
DISPLAY 0.872340 (-575 3000);
PAINT GREEN (-575 3000);
DISPLAY INVISIBLE (-575 3000);
FORCEPROP 1 LAST HDL_TAP TRUE
J 0
(-250 2825);
DISPLAY 0.872340 (-250 2825);
DISPLAY INVISIBLE (-250 2825);
FORCEPROP 1 LAST PATH I92
J 0
(-577 2950);
DISPLAY 0.872340 (-577 2950);
PAINT GREEN (-577 2950);
DISPLAY INVISIBLE (-577 2950);
FORCEADD TAP..1
(-575 3100);
FORCEPROP 3 LASTPIN (-625 3100) SIG_NAME M_B_CPU1_SA_DQ<5>
J 0
(-615 3110);
DISPLAY 0.659574 (-615 3110);
PAINT MONO (-615 3110);
DISPLAY INVISIBLE (-615 3110);
FORCEPROP 1 LASTPIN (-625 3100) BN 5
J 0
(-637 3108);
DISPLAY 0.680851 (-637 3108);
PAINT GREEN (-637 3108);
FORCEPROP 2 LAST CDS_LIB standard
J 0
(-575 3100);
PAINT MONO (-575 3100);
DISPLAY INVISIBLE (-575 3100);
FORCEPROP 1 LAST BODY_TYPE PLUMBING
J 0
(-575 3150);
DISPLAY 0.872340 (-575 3150);
PAINT GREEN (-575 3150);
DISPLAY INVISIBLE (-575 3150);
FORCEPROP 1 LAST HDL_TAP TRUE
J 0
(-250 2975);
DISPLAY 0.872340 (-250 2975);
DISPLAY INVISIBLE (-250 2975);
FORCEPROP 1 LAST PATH I93
J 0
(-577 3100);
DISPLAY 0.872340 (-577 3100);
PAINT GREEN (-577 3100);
DISPLAY INVISIBLE (-577 3100);
FORCEADD TAP..1
(-575 3150);
FORCEPROP 3 LASTPIN (-625 3150) SIG_NAME M_B_CPU1_SA_DQ<6>
J 0
(-615 3160);
DISPLAY 0.659574 (-615 3160);
PAINT MONO (-615 3160);
DISPLAY INVISIBLE (-615 3160);
FORCEPROP 1 LASTPIN (-625 3150) BN 6
J 0
(-637 3158);
DISPLAY 0.680851 (-637 3158);
PAINT GREEN (-637 3158);
FORCEPROP 2 LAST CDS_LIB standard
J 0
(-575 3150);
PAINT MONO (-575 3150);
DISPLAY INVISIBLE (-575 3150);
FORCEPROP 1 LAST BODY_TYPE PLUMBING
J 0
(-575 3200);
DISPLAY 0.872340 (-575 3200);
PAINT GREEN (-575 3200);
DISPLAY INVISIBLE (-575 3200);
FORCEPROP 1 LAST HDL_TAP TRUE
J 0
(-250 3025);
DISPLAY 0.872340 (-250 3025);
DISPLAY INVISIBLE (-250 3025);
FORCEPROP 1 LAST PATH I94
J 0
(-577 3150);
DISPLAY 0.872340 (-577 3150);
PAINT GREEN (-577 3150);
DISPLAY INVISIBLE (-577 3150);
FORCEADD TAP..1
(-575 3300);
FORCEPROP 3 LASTPIN (-625 3300) SIG_NAME M_B_CPU1_SA_DQ<9>
J 0
(-615 3310);
DISPLAY 0.659574 (-615 3310);
PAINT MONO (-615 3310);
DISPLAY INVISIBLE (-615 3310);
FORCEPROP 1 LASTPIN (-625 3300) BN 9
J 0
(-637 3308);
DISPLAY 0.680851 (-637 3308);
PAINT GREEN (-637 3308);
FORCEPROP 2 LAST CDS_LIB standard
J 0
(-575 3300);
PAINT MONO (-575 3300);
DISPLAY INVISIBLE (-575 3300);
FORCEPROP 1 LAST BODY_TYPE PLUMBING
J 0
(-575 3350);
DISPLAY 0.872340 (-575 3350);
PAINT GREEN (-575 3350);
DISPLAY INVISIBLE (-575 3350);
FORCEPROP 1 LAST HDL_TAP TRUE
J 0
(-250 3175);
DISPLAY 0.872340 (-250 3175);
DISPLAY INVISIBLE (-250 3175);
FORCEPROP 1 LAST PATH I95
J 0
(-577 3300);
DISPLAY 0.872340 (-577 3300);
PAINT GREEN (-577 3300);
DISPLAY INVISIBLE (-577 3300);
FORCEADD TAP..1
(-575 3200);
FORCEPROP 3 LASTPIN (-625 3200) SIG_NAME M_B_CPU1_SA_DQ<7>
J 0
(-615 3210);
DISPLAY 0.659574 (-615 3210);
PAINT MONO (-615 3210);
DISPLAY INVISIBLE (-615 3210);
FORCEPROP 1 LASTPIN (-625 3200) BN 7
J 0
(-637 3208);
DISPLAY 0.680851 (-637 3208);
PAINT GREEN (-637 3208);
FORCEPROP 2 LAST CDS_LIB standard
J 0
(-575 3200);
PAINT MONO (-575 3200);
DISPLAY INVISIBLE (-575 3200);
FORCEPROP 1 LAST BODY_TYPE PLUMBING
J 0
(-575 3250);
DISPLAY 0.872340 (-575 3250);
PAINT GREEN (-575 3250);
DISPLAY INVISIBLE (-575 3250);
FORCEPROP 1 LAST HDL_TAP TRUE
J 0
(-250 3075);
DISPLAY 0.872340 (-250 3075);
DISPLAY INVISIBLE (-250 3075);
FORCEPROP 1 LAST PATH I96
J 0
(-577 3200);
DISPLAY 0.872340 (-577 3200);
PAINT GREEN (-577 3200);
DISPLAY INVISIBLE (-577 3200);
FORCEADD TAP..1
(-575 3250);
FORCEPROP 3 LASTPIN (-625 3250) SIG_NAME M_B_CPU1_SA_DQ<8>
J 0
(-615 3260);
DISPLAY 0.659574 (-615 3260);
PAINT MONO (-615 3260);
DISPLAY INVISIBLE (-615 3260);
FORCEPROP 1 LASTPIN (-625 3250) BN 8
J 0
(-637 3258);
DISPLAY 0.680851 (-637 3258);
PAINT GREEN (-637 3258);
FORCEPROP 2 LAST CDS_LIB standard
J 0
(-575 3250);
PAINT MONO (-575 3250);
DISPLAY INVISIBLE (-575 3250);
FORCEPROP 1 LAST BODY_TYPE PLUMBING
J 0
(-575 3300);
DISPLAY 0.872340 (-575 3300);
PAINT GREEN (-575 3300);
DISPLAY INVISIBLE (-575 3300);
FORCEPROP 1 LAST HDL_TAP TRUE
J 0
(-250 3125);
DISPLAY 0.872340 (-250 3125);
DISPLAY INVISIBLE (-250 3125);
FORCEPROP 1 LAST PATH I97
J 0
(-577 3250);
DISPLAY 0.872340 (-577 3250);
PAINT GREEN (-577 3250);
DISPLAY INVISIBLE (-577 3250);
FORCEADD TAP..1
(-575 3500);
FORCEPROP 3 LASTPIN (-625 3500) SIG_NAME M_B_CPU1_SA_DQ<13>
J 0
(-615 3510);
DISPLAY 0.659574 (-615 3510);
PAINT MONO (-615 3510);
DISPLAY INVISIBLE (-615 3510);
FORCEPROP 1 LASTPIN (-625 3500) BN 13
J 0
(-637 3508);
DISPLAY 0.680851 (-637 3508);
PAINT GREEN (-637 3508);
FORCEPROP 2 LAST CDS_LIB standard
J 0
(-575 3500);
PAINT MONO (-575 3500);
DISPLAY INVISIBLE (-575 3500);
FORCEPROP 1 LAST BODY_TYPE PLUMBING
J 0
(-575 3550);
DISPLAY 0.872340 (-575 3550);
PAINT GREEN (-575 3550);
DISPLAY INVISIBLE (-575 3550);
FORCEPROP 1 LAST HDL_TAP TRUE
J 0
(-250 3375);
DISPLAY 0.872340 (-250 3375);
DISPLAY INVISIBLE (-250 3375);
FORCEPROP 1 LAST PATH I98
J 0
(-577 3500);
DISPLAY 0.872340 (-577 3500);
PAINT GREEN (-577 3500);
DISPLAY INVISIBLE (-577 3500);
FORCEADD TAP..1
(-575 3450);
FORCEPROP 3 LASTPIN (-625 3450) SIG_NAME M_B_CPU1_SA_DQ<12>
J 0
(-615 3460);
DISPLAY 0.659574 (-615 3460);
PAINT MONO (-615 3460);
DISPLAY INVISIBLE (-615 3460);
FORCEPROP 1 LASTPIN (-625 3450) BN 12
J 0
(-637 3458);
DISPLAY 0.680851 (-637 3458);
PAINT GREEN (-637 3458);
FORCEPROP 2 LAST CDS_LIB standard
J 0
(-575 3450);
PAINT MONO (-575 3450);
DISPLAY INVISIBLE (-575 3450);
FORCEPROP 1 LAST BODY_TYPE PLUMBING
J 0
(-575 3500);
DISPLAY 0.872340 (-575 3500);
PAINT GREEN (-575 3500);
DISPLAY INVISIBLE (-575 3500);
FORCEPROP 1 LAST HDL_TAP TRUE
J 0
(-250 3325);
DISPLAY 0.872340 (-250 3325);
DISPLAY INVISIBLE (-250 3325);
FORCEPROP 1 LAST PATH I99
J 0
(-577 3450);
DISPLAY 0.872340 (-577 3450);
PAINT GREEN (-577 3450);
DISPLAY INVISIBLE (-577 3450);
FORCEADD CAD_NOTE..1
(1275 -50);
FORCEPROP 0 LAST S1 PLACE THE BYPASS CAPS CLOSE TO DIMM
J 0
(1150 -175);
DISPLAY 1.021277 (1150 -175);
PAINT WHITE (1150 -175);
FORCEPROP 2 LAST CDS_LIB logical_power
J 0
(1275 -50);
PAINT MONO (1275 -50);
DISPLAY INVISIBLE (1275 -50);
FORCEPROP 1 LAST COMMENT_BODY TRUE
J 0
(1300 50);
DISPLAY 0.978723 (1300 50);
DISPLAY INVISIBLE (1300 50);
FORCEADD QUANTA_TITLE_BLOCK_C..1
(5750 -1350);
FORCEPROP 0 LAST CDS_CON_LAST_MODIFIED Fri Aug 25 14:01:20 2023
J 0
(3865 -1335);
PAINT MONO (3865 -1335);
DISPLAY INVISIBLE (3865 -1335);
FORCEPROP 1 LAST CUSTOM_TXT_CDS <CON_LAST_MODIFIED>
J 0
(3865 -1335);
DISPLAY 0.978723 (3865 -1335);
FORCEPROP 2 LAST CUSTOM_TXT_CDS <XR_PAGE_TITLE>
J 0
(-2140 3900);
DISPLAY 0.638298 (-2140 3900);
PAINT PINK (-2140 3900);
DISPLAY INVISIBLE (-2140 3900);
FORCEPROP 2 LAST CUSTOM_TXT_CDS <Q_NUMBER>
J 0
(4347 -1247);
DISPLAY 1.212766 (4347 -1247);
FORCEPROP 2 LAST CUSTOM_TXT_CDS <CON_PAGE_NUM> OF <CON_TOTAL_PAGES>
J 0
(5304 -1332);
DISPLAY 0.978723 (5304 -1332);
FORCEPROP 2 LAST CUSTOM_TXT_CDS <Q_REV>
J 0
(5566 -1247);
DISPLAY 1.212766 (5566 -1247);
FORCEPROP 2 LAST CUSTOM_TXT_CDS <Q_PROJ>
J 0
(3368 -1248);
DISPLAY 1.212766 (3368 -1248);
FORCEPROP 2 LAST CUSTOM_TXT_CDS <NAME_1>
J 0
(2575 -1175);
FORCEPROP 2 LAST CUSTOM_TXT_CDS <NAME_2>
J 0
(2575 -1300);
FORCEPROP 1 LAST Q_TITLE DDR5 - CPU1 CHB DIMM1(YELLOW)
J 0
(-3616 -1324);
DISPLAY 2.446809 (-3616 -1324);
PAINT GREEN (-3616 -1324);
FORCEPROP 1 LAST Q_DEPT 
J 1
(1987 -1301);
DISPLAY 1.957447 (1987 -1301);
PAINT GREEN (1987 -1301);
FORCEPROP 2 LAST CDS_XR_PAGE_TITLE CR-100 : @S9S_MB_2U_LIB.S9S_MB_2U(SCH_1):PAGE100
J 0
(-2140 3900);
DISPLAY 0.638298 (-2140 3900);
PAINT PINK (-2140 3900);
DISPLAY INVISIBLE (-2140 3900);
FORCEPROP 1 LAST COMMENT_BODY TRUE
J 0
(5762 -1363);
DISPLAY 0.978723 (5762 -1363);
PAINT GREEN (5762 -1363);
DISPLAY INVISIBLE (5762 -1363);
FORCEPROP 2 LAST PAGE_BORDER TRUE
J 0
(-2140 3900);
DISPLAY 0.638298 (-2140 3900);
PAINT PINK (-2140 3900);
DISPLAY INVISIBLE (-2140 3900);
FORCEPROP 1 LAST CDS_LMAN_SYM_OUTLINE -9475,6775,100,-125
J 0
(5750 -1350);
DISPLAY 0.468085 (5750 -1350);
PAINT GREEN (5750 -1350);
DISPLAY INVISIBLE (5750 -1350);
FORCEPROP 2 LAST CDS_LIB pure_quanta
J 0
(5750 -1350);
PAINT MONO (5750 -1350);
DISPLAY INVISIBLE (5750 -1350);
WIRE 17 -1 (-525 4375)(-525 4425);
WIRE 17 -1 (-525 4325)(-525 4375);
WIRE 17 -1 (-525 4425)(200 4425);
FORCEPROP 2 LAST SIG_NAME M_B_CPU1_SA_DQ<31:0>
J 0
(-460 4435);
DISPLAY 0.680851 (-460 4435);
PAINT WHITE (-460 4435);
WIRE 17 -1 (-2275 2975)(-2275 3025);
WIRE 17 -1 (-2275 2925)(-2275 2975);
WIRE 17 -1 (-3100 3025)(-2275 3025);
FORCEPROP 2 LAST SIG_NAME M_B_CPU1_SA_CB<7:0>
J 0
(-3010 3035);
DISPLAY 0.680851 (-3010 3035);
PAINT WHITE (-3010 3035);
WIRE 17 -1 (-2275 2725)(-2275 2775);
WIRE 17 -1 (-2275 2675)(-2275 2725);
WIRE 17 -1 (-2275 2775)(-2275 2825);
WIRE 17 -1 (-2275 2825)(-2275 2875);
WIRE 17 -1 (-2275 2875)(-2275 2925);
WIRE 17 -1 (-2275 2525)(-2275 2575);
WIRE 17 -1 (-2275 2475)(-2275 2525);
WIRE 17 -1 (-3100 2575)(-2275 2575);
FORCEPROP 2 LAST SIG_NAME M_B_CPU1_SB_CB<7:0>
J 0
(-3010 2585);
DISPLAY 0.680851 (-3010 2585);
PAINT WHITE (-3010 2585);
WIRE 17 -1 (-2275 4125)(-2275 4175);
WIRE 17 -1 (-2275 4175)(-2275 4225);
WIRE 17 -1 (-2275 4225)(-2275 4275);
WIRE 17 -1 (-2275 4275)(-2275 4325);
WIRE 17 -1 (-2275 4325)(-2275 4375);
WIRE 17 -1 (-2275 4375)(-2275 4425);
WIRE 17 -1 (-3100 4425)(-2275 4425);
FORCEPROP 2 LAST SIG_NAME M_B_CPU1_SA_CA<6:0>
J 0
(-3010 4435);
DISPLAY 0.680851 (-3010 4435);
PAINT WHITE (-3010 4435);
WIRE 17 -1 (-2275 3725)(-2275 3775);
WIRE 17 -1 (-2275 3775)(-2275 3825);
WIRE 17 -1 (-2275 3825)(-2275 3875);
WIRE 17 -1 (-2275 3875)(-2275 3925);
WIRE 17 -1 (-2275 3925)(-2275 3975);
WIRE 17 -1 (-2275 3975)(-2275 4025);
WIRE 17 -1 (-3100 4025)(-2275 4025);
FORCEPROP 2 LAST SIG_NAME M_B_CPU1_SB_CA<6:0>
J 0
(-3010 4035);
DISPLAY 0.680851 (-3010 4035);
PAINT WHITE (-3010 4035);
WIRE 17 -1 (-2275 2425)(-2275 2475);
WIRE 17 -1 (-2275 2375)(-2275 2425);
WIRE 17 -1 (-2275 2325)(-2275 2375);
WIRE 17 -1 (-2275 2275)(-2275 2325);
WIRE 17 -1 (-525 4275)(-525 4325);
WIRE 17 -1 (-525 4225)(-525 4275);
WIRE 17 -1 (-525 4175)(-525 4225);
WIRE 17 -1 (-525 4125)(-525 4175);
WIRE 17 -1 (-525 4075)(-525 4125);
WIRE 17 -1 (-525 4025)(-525 4075);
WIRE 17 -1 (-525 3975)(-525 4025);
WIRE 17 -1 (-525 3925)(-525 3975);
WIRE 17 -1 (-525 3875)(-525 3925);
WIRE 17 -1 (-525 3825)(-525 3875);
WIRE 17 -1 (-525 3775)(-525 3825);
WIRE 17 -1 (-525 3725)(-525 3775);
WIRE 17 -1 (-525 3675)(-525 3725);
WIRE 17 -1 (-525 3625)(-525 3675);
WIRE 17 -1 (-525 3575)(-525 3625);
WIRE 17 -1 (-525 3525)(-525 3575);
WIRE 17 -1 (-525 3475)(-525 3525);
WIRE 17 -1 (-525 3425)(-525 3475);
WIRE 17 -1 (-525 3375)(-525 3425);
WIRE 17 -1 (-525 3325)(-525 3375);
WIRE 17 -1 (-525 3275)(-525 3325);
WIRE 17 -1 (-525 3225)(-525 3275);
WIRE 17 -1 (-525 3175)(-525 3225);
WIRE 17 -1 (-525 3125)(-525 3175);
WIRE 17 -1 (-525 3075)(-525 3125);
WIRE 17 -1 (-525 3025)(-525 3075);
WIRE 17 -1 (-525 2975)(-525 3025);
WIRE 17 -1 (-525 2925)(-525 2975);
WIRE 17 -1 (-525 2875)(-525 2925);
WIRE 17 -1 (-525 2725)(-525 2775);
WIRE 17 -1 (-525 2675)(-525 2725);
WIRE 17 -1 (-525 2775)(200 2775);
FORCEPROP 2 LAST SIG_NAME M_B_CPU1_SB_DQ<31:0>
J 0
(-460 2785);
DISPLAY 0.680851 (-460 2785);
PAINT WHITE (-460 2785);
WIRE 17 -1 (-525 2625)(-525 2675);
WIRE 17 -1 (-525 2575)(-525 2625);
WIRE 17 -1 (-525 2525)(-525 2575);
WIRE 17 -1 (-525 2475)(-525 2525);
WIRE 17 -1 (-525 2425)(-525 2475);
WIRE 17 -1 (-525 2375)(-525 2425);
WIRE 17 -1 (-525 2325)(-525 2375);
WIRE 17 -1 (-525 2275)(-525 2325);
WIRE 17 -1 (-525 2225)(-525 2275);
WIRE 17 -1 (-525 2175)(-525 2225);
WIRE 17 -1 (-525 2125)(-525 2175);
WIRE 17 -1 (-525 2075)(-525 2125);
WIRE 17 -1 (-525 2025)(-525 2075);
WIRE 17 -1 (-525 1975)(-525 2025);
WIRE 17 -1 (-525 1925)(-525 1975);
WIRE 17 -1 (-525 1875)(-525 1925);
WIRE 17 -1 (-525 1825)(-525 1875);
WIRE 17 -1 (-525 1775)(-525 1825);
WIRE 17 -1 (-525 1725)(-525 1775);
WIRE 17 -1 (-525 1675)(-525 1725);
WIRE 17 -1 (-525 1625)(-525 1675);
WIRE 17 -1 (-525 1575)(-525 1625);
WIRE 17 -1 (-525 1525)(-525 1575);
WIRE 17 -1 (-525 1475)(-525 1525);
WIRE 17 -1 (-525 1425)(-525 1475);
WIRE 17 -1 (-525 1375)(-525 1425);
WIRE 17 -1 (-525 1325)(-525 1375);
WIRE 17 -1 (-525 1275)(-525 1325);
WIRE 17 -1 (-525 1225)(-525 1275);
WIRE 17 -1 (-2275 2225)(-2275 2275);
WIRE 17 -1 (2225 2475)(2225 2575);
WIRE 17 -1 (2225 2575)(2225 2675);
WIRE 17 -1 (2225 2675)(2225 2775);
WIRE 17 -1 (2225 2875)(2225 2775);
WIRE 17 -1 (2225 2875)(2225 2975);
WIRE 17 -1 (2225 2975)(2225 3075);
WIRE 17 -1 (2225 3075)(2225 3175);
WIRE 17 -1 (2225 3175)(2225 3275);
WIRE 17 -1 (2225 3275)(2225 3375);
WIRE 17 -1 (2225 3375)(3250 3375);
FORCEPROP 2 LAST SIG_NAME M_B_CPU1_SB_DQS_DP<9:0>
J 0
(2465 3385);
DISPLAY 0.680851 (2465 3385);
PAINT WHITE (2465 3385);
WIRE 17 -1 (2225 3525)(2225 3625);
WIRE 17 -1 (2225 3625)(2225 3725);
WIRE 17 -1 (2225 3725)(2225 3825);
WIRE 17 -1 (2225 3925)(2225 3825);
WIRE 17 -1 (2225 3925)(2225 4025);
WIRE 17 -1 (2225 4025)(2225 4125);
WIRE 17 -1 (2225 4125)(2225 4225);
WIRE 17 -1 (2225 4225)(2225 4325);
WIRE 17 -1 (2225 4325)(2225 4425);
WIRE 17 -1 (2225 4425)(3250 4425);
FORCEPROP 2 LAST SIG_NAME M_B_CPU1_SA_DQS_DP<9:0>
J 0
(2465 4435);
DISPLAY 0.680851 (2465 4435);
PAINT WHITE (2465 4435);
WIRE 17 -1 (2400 2525)(2400 2625);
WIRE 17 -1 (2400 2425)(2400 2525);
WIRE 17 -1 (2400 2625)(2400 2725);
WIRE 17 -1 (2400 2825)(2400 2725);
WIRE 17 -1 (2400 2825)(2400 2925);
WIRE 17 -1 (2400 2925)(2400 3025);
WIRE 17 -1 (2400 3025)(2400 3125);
WIRE 17 -1 (2400 3125)(2400 3225);
WIRE 17 -1 (2400 3225)(2400 3325);
WIRE 17 -1 (2400 3325)(3250 3325);
FORCEPROP 2 LAST SIG_NAME M_B_CPU1_SB_DQS_DN<9:0>
J 0
(2465 3335);
DISPLAY 0.680851 (2465 3335);
PAINT WHITE (2465 3335);
WIRE 17 -1 (2400 3475)(2400 3575);
WIRE 17 -1 (2400 3575)(2400 3675);
WIRE 17 -1 (2400 3675)(2400 3775);
WIRE 17 -1 (2400 3875)(2400 3775);
WIRE 17 -1 (2400 3875)(2400 3975);
WIRE 17 -1 (2400 3975)(2400 4075);
WIRE 17 -1 (2400 4075)(2400 4175);
WIRE 17 -1 (2400 4175)(2400 4275);
WIRE 17 -1 (2400 4275)(2400 4375);
WIRE 17 -1 (2400 4375)(3250 4375);
FORCEPROP 2 LAST SIG_NAME M_B_CPU1_SA_DQS_DN<9:0>
J 0
(2465 4385);
DISPLAY 0.680851 (2465 4385);
PAINT WHITE (2465 4385);
WIRE 16 -1 (1150 625)(1150 800);
WIRE 16 -1 (2150 800)(2150 750);
WIRE 16 -1 (3850 4900)(3850 4400);
WIRE 16 -1 (-3050 2225)(-3050 1950);
WIRE 16 -1 (1150 425)(1150 200);
WIRE 16 -1 (2775 200)(2775 275);
WIRE 16 -1 (3850 750)(3850 1150);
WIRE 16 -1 (5550 1050)(5550 750);
WIRE 16 -1 (5550 1100)(5550 1050);
WIRE 16 -1 (5300 1050)(5550 1050);
WIRE 16 -1 (-2000 75)(-2000 150);
WIRE 16 3135 (800 1025)(800 -275);
WIRE 16 3135 (3400 1025)(800 1025);
WIRE 16 3135 (800 -275)(3400 -275);
WIRE 16 3135 (3400 -275)(3400 1025);
WIRE 16 -1 (-2000 1900)(-3025 1900);
FORCEPROP 2 LAST SIG_NAME PD_CHB_CPU1_DIMM1_SAA
J 0
(-3035 1910);
DISPLAY 0.680851 (-3035 1910);
PAINT WHITE (-3035 1910);
WIRE 16 -1 (-2000 1850)(-3025 1850);
FORCEPROP 2 LAST SIG_NAME I3C_SPD_DDRABCD_CPU1_LVC1_SDA
J 0
(-3035 1860);
DISPLAY 0.680851 (-3035 1860);
PAINT WHITE (-3035 1860);
WIRE 16 -1 (-3050 1950)(-2000 1950);
WIRE 16 -1 (-2000 2050)(-3100 2050);
FORCEPROP 2 LAST SIG_NAME M_B_CPU1_ALERT_N
J 0
(-3012 2059);
DISPLAY 0.680851 (-3012 2059);
PAINT WHITE (-3012 2059);
WIRE 16 -1 (-2400 2100)(-2000 2100);
WIRE 16 -1 (-2400 2150)(-3100 2150);
FORCEPROP 2 LAST SIG_NAME RST_M_AB_CPU1_FPGA_N
J 0
(-3012 2159);
DISPLAY 0.680851 (-3012 2159);
PAINT WHITE (-3012 2159);
WIRE 16 -1 (-2400 2150)(-2400 2100);
WIRE 16 -1 (-3475 1675)(-3275 1675);
WIRE 16 -1 (-3475 1675)(-3475 1800);
WIRE 16 -1 (-2000 1800)(-3475 1800);
FORCEPROP 2 LAST SIG_NAME I3C_SPD_DDRABCD_CPU1_LVC1_SCL_R3
J 0
(-3060 1810);
DISPLAY 0.680851 (-3060 1810);
PAINT WHITE (-3060 1810);
WIRE 16 -1 (-1875 1625)(-1900 1625);
WIRE 16 -1 (-1875 1675)(-1875 1625);
WIRE 16 -1 (-3075 1675)(-1875 1675);
FORCEPROP 2 LAST SIG_NAME I3C_SPD_DDRABCD_CPU1_LVC1_SCL
J 0
(-2910 1685);
DISPLAY 0.680851 (-2910 1685);
PAINT WHITE (-2910 1685);
WIRE 16 -1 (-2000 1550)(-3100 1550);
FORCEPROP 2 LAST SIG_NAME PWRGD_CHB_CPU1_DIMM1
J 0
(-3012 1559);
DISPLAY 0.680851 (-3012 1559);
PAINT WHITE (-3012 1559);
WIRE 16 -1 (-2000 1450)(-3100 1450);
FORCEPROP 2 LAST SIG_NAME TP_CHB_CPU1_DIMM1_FRU_6
J 0
(-3012 1459);
DISPLAY 0.680851 (-3012 1459);
PAINT WHITE (-3012 1459);
WIRE 16 -1 (-2000 1250)(-3100 1250);
FORCEPROP 2 LAST SIG_NAME TP_CHB_CPU1_DIMM1_FRU_2
J 0
(-3012 1259);
DISPLAY 0.680851 (-3012 1259);
PAINT WHITE (-3012 1259);
WIRE 16 -1 (-2000 1400)(-3100 1400);
FORCEPROP 2 LAST SIG_NAME TP_CHB_CPU1_DIMM1_FRU_5
J 0
(-3012 1409);
DISPLAY 0.680851 (-3012 1409);
PAINT WHITE (-3012 1409);
WIRE 16 -1 (-2000 1300)(-3100 1300);
FORCEPROP 2 LAST SIG_NAME TP_CHB_CPU1_DIMM1_FRU_3
J 0
(-3012 1309);
DISPLAY 0.680851 (-3012 1309);
PAINT WHITE (-3012 1309);
WIRE 16 -1 (-2000 1200)(-3100 1200);
FORCEPROP 2 LAST SIG_NAME TP_CHB_CPU1_DIMM1_FRU_1
J 0
(-3012 1209);
DISPLAY 0.680851 (-3012 1209);
PAINT WHITE (-3012 1209);
WIRE 16 -1 (-2000 1150)(-3100 1150);
FORCEPROP 2 LAST SIG_NAME TP_CHB_CPU1_DIMM1_FRU_0
J 0
(-3012 1159);
DISPLAY 0.680851 (-3012 1159);
PAINT WHITE (-3012 1159);
WIRE 16 -1 (2025 2800)(2300 2800);
WIRE 16 -1 (2025 4250)(2300 4250);
WIRE 16 -1 (2025 4350)(2300 4350);
WIRE 16 -1 (2025 4150)(2300 4150);
WIRE 16 -1 (2025 4050)(2300 4050);
WIRE 16 -1 (2025 3950)(2300 3950);
WIRE 16 -1 (2025 3850)(2300 3850);
WIRE 16 -1 (2025 3750)(2300 3750);
WIRE 16 -1 (2025 3650)(2300 3650);
WIRE 16 -1 (2025 3550)(2300 3550);
WIRE 16 -1 (2025 3450)(2300 3450);
WIRE 16 -1 (2025 3300)(2300 3300);
WIRE 16 -1 (2025 3200)(2300 3200);
WIRE 16 -1 (2025 3100)(2300 3100);
WIRE 16 -1 (2025 3000)(2300 3000);
WIRE 16 -1 (2025 2900)(2300 2900);
WIRE 16 -1 (2025 2700)(2300 2700);
WIRE 16 -1 (2025 2600)(2300 2600);
WIRE 16 -1 (2025 2400)(2300 2400);
WIRE 16 -1 (2025 2500)(2300 2500);
WIRE 16 -1 (2025 4400)(2125 4400);
WIRE 16 -1 (2025 4300)(2125 4300);
WIRE 16 -1 (2025 4200)(2125 4200);
WIRE 16 -1 (2025 4100)(2125 4100);
WIRE 16 -1 (2025 4000)(2125 4000);
WIRE 16 -1 (2025 3900)(2125 3900);
WIRE 16 -1 (2025 3800)(2125 3800);
WIRE 16 -1 (2025 3700)(2125 3700);
WIRE 16 -1 (2025 3600)(2125 3600);
WIRE 16 -1 (2025 3500)(2125 3500);
WIRE 16 -1 (2025 3350)(2125 3350);
WIRE 16 -1 (2025 3250)(2125 3250);
WIRE 16 -1 (2025 3150)(2125 3150);
WIRE 16 -1 (2025 3050)(2125 3050);
WIRE 16 -1 (2025 2950)(2125 2950);
WIRE 16 -1 (2025 2850)(2125 2850);
WIRE 16 -1 (2025 2750)(2125 2750);
WIRE 16 -1 (2025 2650)(2125 2650);
WIRE 16 -1 (2025 2550)(2125 2550);
WIRE 16 -1 (2025 2450)(2125 2450);
WIRE 16 -1 (-2175 2200)(-2000 2200);
WIRE 16 -1 (-2175 2250)(-2000 2250);
WIRE 16 -1 (-2175 2300)(-2000 2300);
WIRE 16 -1 (-2175 2350)(-2000 2350);
WIRE 16 -1 (4100 4400)(3850 4400);
WIRE 16 -1 (3850 4400)(3850 4350);
WIRE 16 -1 (3850 4350)(4100 4350);
WIRE 16 -1 (3850 4350)(3850 4300);
WIRE 16 -1 (4100 4300)(3850 4300);
WIRE 16 -1 (-800 4300)(-625 4300);
WIRE 16 -1 (-800 3350)(-625 3350);
WIRE 16 -1 (-2000 3250)(-3100 3250);
FORCEPROP 2 LAST SIG_NAME M_B_CPU1_SB_CS_N<0>
J 0
(-3012 3259);
DISPLAY 0.680851 (-3012 3259);
PAINT WHITE (-3012 3259);
WIRE 16 -1 (-2000 3150)(-3100 3150);
FORCEPROP 2 LAST SIG_NAME M_B_CPU1_CLK_DP<0>
J 0
(-3012 3159);
DISPLAY 0.680851 (-3012 3159);
PAINT WHITE (-3012 3159);
WIRE 16 -1 (-2000 3100)(-3100 3100);
FORCEPROP 2 LAST SIG_NAME M_B_CPU1_CLK_DN<0>
J 0
(-3012 3109);
DISPLAY 0.680851 (-3012 3109);
PAINT WHITE (-3012 3109);
WIRE 16 -1 (-2175 2850)(-2000 2850);
WIRE 16 -1 (-800 2700)(-625 2700);
WIRE 16 -1 (3850 1150)(4100 1150);
WIRE 16 -1 (3850 1150)(3850 1200);
WIRE 16 -1 (3850 1200)(4100 1200);
WIRE 16 -1 (3850 1200)(3850 1250);
WIRE 16 -1 (3850 1250)(4100 1250);
WIRE 16 -1 (3850 1250)(3850 1300);
WIRE 16 -1 (3850 1300)(4100 1300);
WIRE 16 -1 (3850 1300)(3850 1350);
WIRE 16 -1 (3850 1350)(4100 1350);
WIRE 16 -1 (3850 1350)(3850 1400);
WIRE 16 -1 (3850 1400)(4100 1400);
WIRE 16 -1 (3850 1400)(3850 1450);
WIRE 16 -1 (3850 1450)(4100 1450);
WIRE 16 -1 (3850 1450)(3850 1500);
WIRE 16 -1 (3850 1500)(4100 1500);
WIRE 16 -1 (3850 1500)(3850 1550);
WIRE 16 -1 (3850 1550)(4100 1550);
WIRE 16 -1 (3850 1550)(3850 1600);
WIRE 16 -1 (3850 1600)(4100 1600);
WIRE 16 -1 (3850 1600)(3850 1650);
WIRE 16 -1 (4100 1650)(3850 1650);
WIRE 16 -1 (3850 1650)(3850 1700);
WIRE 16 -1 (3850 1700)(4100 1700);
WIRE 16 -1 (3850 1700)(3850 1750);
WIRE 16 -1 (3850 1750)(4100 1750);
WIRE 16 -1 (3850 1750)(3850 1800);
WIRE 16 -1 (3850 1800)(4100 1800);
WIRE 16 -1 (3850 1800)(3850 1850);
WIRE 16 -1 (3850 1850)(4100 1850);
WIRE 16 -1 (3850 1850)(3850 1900);
WIRE 16 -1 (3850 1900)(4100 1900);
WIRE 16 -1 (3850 1900)(3850 1950);
WIRE 16 -1 (3850 1950)(4100 1950);
WIRE 16 -1 (3850 1950)(3850 2000);
WIRE 16 -1 (3850 2000)(4100 2000);
WIRE 16 -1 (3850 2000)(3850 2050);
WIRE 16 -1 (3850 2050)(4100 2050);
WIRE 16 -1 (3850 2050)(3850 2100);
WIRE 16 -1 (3850 2100)(4100 2100);
WIRE 16 -1 (3850 2100)(3850 2150);
WIRE 16 -1 (4100 2150)(3850 2150);
WIRE 16 -1 (3850 2150)(3850 2200);
WIRE 16 -1 (3850 2200)(4100 2200);
WIRE 16 -1 (3850 2200)(3850 2250);
WIRE 16 -1 (3850 2250)(4100 2250);
WIRE 16 -1 (3850 2250)(3850 2300);
WIRE 16 -1 (3850 2300)(4100 2300);
WIRE 16 -1 (3850 2300)(3850 2350);
WIRE 16 -1 (3850 2350)(4100 2350);
WIRE 16 -1 (3850 2350)(3850 2400);
WIRE 16 -1 (3850 2400)(4100 2400);
WIRE 16 -1 (3850 2400)(3850 2450);
WIRE 16 -1 (3850 2450)(4100 2450);
WIRE 16 -1 (3850 2450)(3850 2500);
WIRE 16 -1 (3850 2500)(4100 2500);
WIRE 16 -1 (3850 2500)(3850 2550);
WIRE 16 -1 (3850 2550)(4100 2550);
WIRE 16 -1 (3850 2550)(3850 2600);
WIRE 16 -1 (3850 2600)(4100 2600);
WIRE 16 -1 (3850 2600)(3850 2650);
WIRE 16 -1 (4100 2650)(3850 2650);
WIRE 16 -1 (3850 2650)(3850 2700);
WIRE 16 -1 (3850 2700)(4100 2700);
WIRE 16 -1 (3850 2700)(3850 2750);
WIRE 16 -1 (3850 2750)(4100 2750);
WIRE 16 -1 (3850 2750)(3850 2800);
WIRE 16 -1 (3850 2800)(4100 2800);
WIRE 16 -1 (3850 2800)(3850 2850);
WIRE 16 -1 (3850 2850)(4100 2850);
WIRE 16 -1 (3850 2850)(3850 2900);
WIRE 16 -1 (3850 2900)(4100 2900);
WIRE 16 -1 (3850 2900)(3850 2950);
WIRE 16 -1 (3850 2950)(4100 2950);
WIRE 16 -1 (3850 2950)(3850 3000);
WIRE 16 -1 (3850 3000)(4100 3000);
WIRE 16 -1 (3850 3000)(3850 3050);
WIRE 16 -1 (3850 3050)(4100 3050);
WIRE 16 -1 (3850 3050)(3850 3100);
WIRE 16 -1 (3850 3100)(4100 3100);
WIRE 16 -1 (3850 3100)(3850 3150);
WIRE 16 -1 (4100 3150)(3850 3150);
WIRE 16 -1 (3850 3150)(3850 3200);
WIRE 16 -1 (3850 3200)(4100 3200);
WIRE 16 -1 (3850 3200)(3850 3250);
WIRE 16 -1 (3850 3250)(4100 3250);
WIRE 16 -1 (3850 3250)(3850 3300);
WIRE 16 -1 (3850 3300)(4100 3300);
WIRE 16 -1 (3850 3300)(3850 3350);
WIRE 16 -1 (3850 3350)(4100 3350);
WIRE 16 -1 (3850 3350)(3850 3400);
WIRE 16 -1 (3850 3400)(4100 3400);
WIRE 16 -1 (3850 3400)(3850 3450);
WIRE 16 -1 (3850 3450)(4100 3450);
WIRE 16 -1 (3850 3450)(3850 3500);
WIRE 16 -1 (3850 3500)(4100 3500);
WIRE 16 -1 (3850 3500)(3850 3550);
WIRE 16 -1 (3850 3550)(4100 3550);
WIRE 16 -1 (3850 3550)(3850 3600);
WIRE 16 -1 (3850 3600)(4100 3600);
WIRE 16 -1 (3850 3600)(3850 3650);
WIRE 16 -1 (4100 3650)(3850 3650);
WIRE 16 -1 (3850 3650)(3850 3700);
WIRE 16 -1 (3850 3700)(4100 3700);
WIRE 16 -1 (3850 3700)(3850 3750);
WIRE 16 -1 (3850 3750)(4100 3750);
WIRE 16 -1 (3850 3750)(3850 3800);
WIRE 16 -1 (3850 3800)(4100 3800);
WIRE 16 -1 (3850 3800)(3850 3850);
WIRE 16 -1 (3850 3850)(4100 3850);
WIRE 16 -1 (3850 3850)(3850 3900);
WIRE 16 -1 (3850 3900)(4100 3900);
WIRE 16 -1 (3850 3900)(3850 3950);
WIRE 16 -1 (3850 3950)(4100 3950);
WIRE 16 -1 (3850 3950)(3850 4000);
WIRE 16 -1 (3850 4000)(4100 4000);
WIRE 16 -1 (3850 4000)(3850 4050);
WIRE 16 -1 (3850 4050)(4100 4050);
WIRE 16 -1 (3850 4050)(3850 4100);
WIRE 16 -1 (3850 4100)(4100 4100);
WIRE 16 -1 (3850 4100)(3850 4150);
WIRE 16 -1 (4100 4150)(3850 4150);
WIRE 16 -1 (3850 4150)(3850 4200);
WIRE 16 -1 (3850 4200)(4100 4200);
WIRE 16 -1 (3850 4200)(3850 4250);
WIRE 16 -1 (4100 4250)(3850 4250);
WIRE 16 -1 (5300 4400)(5550 4400);
WIRE 16 -1 (5300 4350)(5550 4350);
WIRE 16 -1 (5550 4400)(5550 4350);
WIRE 16 -1 (5300 4300)(5550 4300);
WIRE 16 -1 (5550 4350)(5550 4300);
WIRE 16 -1 (5300 4250)(5550 4250);
WIRE 16 -1 (5550 4300)(5550 4250);
WIRE 16 -1 (5300 4200)(5550 4200);
WIRE 16 -1 (5550 4250)(5550 4200);
WIRE 16 -1 (5300 4150)(5550 4150);
WIRE 16 -1 (5550 4200)(5550 4150);
WIRE 16 -1 (5300 4100)(5550 4100);
WIRE 16 -1 (5550 4150)(5550 4100);
WIRE 16 -1 (5300 4050)(5550 4050);
WIRE 16 -1 (5550 4100)(5550 4050);
WIRE 16 -1 (5300 4000)(5550 4000);
WIRE 16 -1 (5550 4050)(5550 4000);
WIRE 16 -1 (5300 3950)(5550 3950);
WIRE 16 -1 (5550 4000)(5550 3950);
WIRE 16 -1 (5300 3900)(5550 3900);
WIRE 16 -1 (5550 3950)(5550 3900);
WIRE 16 -1 (5300 3850)(5550 3850);
WIRE 16 -1 (5550 3900)(5550 3850);
WIRE 16 -1 (5300 3800)(5550 3800);
WIRE 16 -1 (5550 3850)(5550 3800);
WIRE 16 -1 (5300 3750)(5550 3750);
WIRE 16 -1 (5550 3800)(5550 3750);
WIRE 16 -1 (5300 3700)(5550 3700);
WIRE 16 -1 (5550 3750)(5550 3700);
WIRE 16 -1 (5300 3650)(5550 3650);
WIRE 16 -1 (5550 3650)(5550 3700);
WIRE 16 -1 (5300 3600)(5550 3600);
WIRE 16 -1 (5550 3650)(5550 3600);
WIRE 16 -1 (5550 3550)(5300 3550);
WIRE 16 -1 (5550 3600)(5550 3550);
WIRE 16 -1 (5550 3500)(5300 3500);
WIRE 16 -1 (5550 3550)(5550 3500);
WIRE 16 -1 (5300 3450)(5550 3450);
WIRE 16 -1 (5550 3500)(5550 3450);
WIRE 16 -1 (5300 3400)(5550 3400);
WIRE 16 -1 (5550 3450)(5550 3400);
WIRE 16 -1 (5300 3350)(5550 3350);
WIRE 16 -1 (5550 3400)(5550 3350);
WIRE 16 -1 (5300 3300)(5550 3300);
WIRE 16 -1 (5550 3350)(5550 3300);
WIRE 16 -1 (5300 3250)(5550 3250);
WIRE 16 -1 (5550 3300)(5550 3250);
WIRE 16 -1 (5300 3200)(5550 3200);
WIRE 16 -1 (5550 3250)(5550 3200);
WIRE 16 -1 (5300 3150)(5550 3150);
WIRE 16 -1 (5550 3150)(5550 3200);
WIRE 16 -1 (5300 3100)(5550 3100);
WIRE 16 -1 (5550 3150)(5550 3100);
WIRE 16 -1 (5550 3050)(5300 3050);
WIRE 16 -1 (5550 3100)(5550 3050);
WIRE 16 -1 (5550 3000)(5300 3000);
WIRE 16 -1 (5550 3050)(5550 3000);
WIRE 16 -1 (5300 2950)(5550 2950);
WIRE 16 -1 (5550 3000)(5550 2950);
WIRE 16 -1 (5300 2900)(5550 2900);
WIRE 16 -1 (5550 2950)(5550 2900);
WIRE 16 -1 (5300 2850)(5550 2850);
WIRE 16 -1 (5550 2900)(5550 2850);
WIRE 16 -1 (5300 2800)(5550 2800);
WIRE 16 -1 (5550 2850)(5550 2800);
WIRE 16 -1 (5300 2750)(5550 2750);
WIRE 16 -1 (5550 2800)(5550 2750);
WIRE 16 -1 (5300 2700)(5550 2700);
WIRE 16 -1 (5550 2750)(5550 2700);
WIRE 16 -1 (5300 2650)(5550 2650);
WIRE 16 -1 (5550 2650)(5550 2700);
WIRE 16 -1 (5300 2600)(5550 2600);
WIRE 16 -1 (5550 2650)(5550 2600);
WIRE 16 -1 (5550 2550)(5300 2550);
WIRE 16 -1 (5550 2600)(5550 2550);
WIRE 16 -1 (5550 2500)(5300 2500);
WIRE 16 -1 (5550 2550)(5550 2500);
WIRE 16 -1 (5300 2450)(5550 2450);
WIRE 16 -1 (5550 2500)(5550 2450);
WIRE 16 -1 (5300 2400)(5550 2400);
WIRE 16 -1 (5550 2450)(5550 2400);
WIRE 16 -1 (5300 2350)(5550 2350);
WIRE 16 -1 (5550 2400)(5550 2350);
WIRE 16 -1 (5300 2300)(5550 2300);
WIRE 16 -1 (5550 2350)(5550 2300);
WIRE 16 -1 (5300 2250)(5550 2250);
WIRE 16 -1 (5550 2300)(5550 2250);
WIRE 16 -1 (5300 2200)(5550 2200);
WIRE 16 -1 (5550 2250)(5550 2200);
WIRE 16 -1 (5300 2150)(5550 2150);
WIRE 16 -1 (5550 2150)(5550 2200);
WIRE 16 -1 (5300 2100)(5550 2100);
WIRE 16 -1 (5550 2150)(5550 2100);
WIRE 16 -1 (5550 2050)(5300 2050);
WIRE 16 -1 (5550 2100)(5550 2050);
WIRE 16 -1 (5550 2000)(5300 2000);
WIRE 16 -1 (5550 2050)(5550 2000);
WIRE 16 -1 (5550 1950)(5300 1950);
WIRE 16 -1 (5550 2000)(5550 1950);
WIRE 16 -1 (5550 1900)(5300 1900);
WIRE 16 -1 (5550 1950)(5550 1900);
WIRE 16 -1 (5300 1850)(5550 1850);
WIRE 16 -1 (5550 1850)(5550 1900);
WIRE 16 -1 (5550 1800)(5300 1800);
WIRE 16 -1 (5550 1800)(5550 1850);
WIRE 16 -1 (5550 1750)(5300 1750);
WIRE 16 -1 (5550 1800)(5550 1750);
WIRE 16 -1 (5550 1700)(5300 1700);
WIRE 16 -1 (5550 1750)(5550 1700);
WIRE 16 -1 (5300 1650)(5550 1650);
WIRE 16 -1 (5550 1700)(5550 1650);
WIRE 16 -1 (5300 1600)(5550 1600);
WIRE 16 -1 (5550 1650)(5550 1600);
WIRE 16 -1 (5300 1550)(5550 1550);
WIRE 16 -1 (5550 1600)(5550 1550);
WIRE 16 -1 (5300 1500)(5550 1500);
WIRE 16 -1 (5550 1550)(5550 1500);
WIRE 16 -1 (5300 1450)(5550 1450);
WIRE 16 -1 (5550 1500)(5550 1450);
WIRE 16 -1 (5300 1400)(5550 1400);
WIRE 16 -1 (5550 1450)(5550 1400);
WIRE 16 -1 (5300 1350)(5550 1350);
WIRE 16 -1 (5550 1400)(5550 1350);
WIRE 16 -1 (5300 1300)(5550 1300);
WIRE 16 -1 (5550 1300)(5550 1350);
WIRE 16 -1 (5300 1250)(5550 1250);
WIRE 16 -1 (5550 1300)(5550 1250);
WIRE 16 -1 (5300 1150)(5550 1150);
WIRE 16 -1 (5550 1250)(5550 1150);
WIRE 16 -1 (5550 1150)(5550 1100);
WIRE 16 -1 (5300 1100)(5550 1100);
WIRE 16 -1 (-2000 1350)(-3100 1350);
FORCEPROP 2 LAST SIG_NAME TP_CHB_CPU1_DIMM1_FRU_4
J 0
(-3012 1359);
DISPLAY 0.680851 (-3012 1359);
PAINT WHITE (-3012 1359);
WIRE 16 -1 (-2000 3550)(-3100 3550);
FORCEPROP 2 LAST SIG_NAME M_B_CPU1_SB_PAR
J 0
(-3012 3559);
DISPLAY 0.680851 (-3012 3559);
PAINT WHITE (-3012 3559);
WIRE 16 -1 (-2000 3600)(-3100 3600);
FORCEPROP 2 LAST SIG_NAME M_B_CPU1_SA_PAR
J 0
(-3012 3609);
DISPLAY 0.680851 (-3012 3609);
PAINT WHITE (-3012 3609);
WIRE 16 -1 (-2000 950)(-3100 950);
FORCEPROP 2 LAST SIG_NAME M_B_CPU1_SB_RSP<0>
J 0
(-3012 959);
DISPLAY 0.680851 (-3012 959);
PAINT WHITE (-3012 959);
WIRE 16 -1 (-2000 1000)(-3100 1000);
FORCEPROP 2 LAST SIG_NAME M_B_CPU1_SA_RSP<0>
J 0
(-3012 1009);
DISPLAY 0.680851 (-3012 1009);
PAINT WHITE (-3012 1009);
WIRE 16 -1 (-800 1200)(-625 1200);
WIRE 16 -1 (-800 1250)(-625 1250);
WIRE 16 -1 (-800 1300)(-625 1300);
WIRE 16 -1 (-800 1350)(-625 1350);
WIRE 16 -1 (-800 1400)(-625 1400);
WIRE 16 -1 (-800 1450)(-625 1450);
WIRE 16 -1 (-800 1500)(-625 1500);
WIRE 16 -1 (-800 1550)(-625 1550);
WIRE 16 -1 (-800 1600)(-625 1600);
WIRE 16 -1 (-800 1650)(-625 1650);
WIRE 16 -1 (-800 1700)(-625 1700);
WIRE 16 -1 (-800 1750)(-625 1750);
WIRE 16 -1 (-800 1800)(-625 1800);
WIRE 16 -1 (-800 1850)(-625 1850);
WIRE 16 -1 (-800 1900)(-625 1900);
WIRE 16 -1 (-800 1950)(-625 1950);
WIRE 16 -1 (-800 2000)(-625 2000);
WIRE 16 -1 (-800 2050)(-625 2050);
WIRE 16 -1 (-800 2100)(-625 2100);
WIRE 16 -1 (-800 2150)(-625 2150);
WIRE 16 -1 (-800 2200)(-625 2200);
WIRE 16 -1 (-800 2250)(-625 2250);
WIRE 16 -1 (-800 2300)(-625 2300);
WIRE 16 -1 (-800 2350)(-625 2350);
WIRE 16 -1 (-800 2400)(-625 2400);
WIRE 16 -1 (-800 2450)(-625 2450);
WIRE 16 -1 (-800 2500)(-625 2500);
WIRE 16 -1 (-800 2550)(-625 2550);
WIRE 16 -1 (-800 2600)(-625 2600);
WIRE 16 -1 (-800 2650)(-625 2650);
WIRE 16 -1 (-800 2750)(-625 2750);
WIRE 16 -1 (-800 2850)(-625 2850);
WIRE 16 -1 (-800 2900)(-625 2900);
WIRE 16 -1 (-800 2950)(-625 2950);
WIRE 16 -1 (-800 3000)(-625 3000);
WIRE 16 -1 (-800 3050)(-625 3050);
WIRE 16 -1 (-800 3100)(-625 3100);
WIRE 16 -1 (-800 3150)(-625 3150);
WIRE 16 -1 (-800 3200)(-625 3200);
WIRE 16 -1 (-800 3250)(-625 3250);
WIRE 16 -1 (-800 3300)(-625 3300);
WIRE 16 -1 (-800 3400)(-625 3400);
WIRE 16 -1 (-800 3450)(-625 3450);
WIRE 16 -1 (-800 3500)(-625 3500);
WIRE 16 -1 (-800 3550)(-625 3550);
WIRE 16 -1 (-800 3600)(-625 3600);
WIRE 16 -1 (-800 3650)(-625 3650);
WIRE 16 -1 (-800 3700)(-625 3700);
WIRE 16 -1 (-800 3750)(-625 3750);
WIRE 16 -1 (-800 3800)(-625 3800);
WIRE 16 -1 (-800 3850)(-625 3850);
WIRE 16 -1 (-800 3900)(-625 3900);
WIRE 16 -1 (-800 3950)(-625 3950);
WIRE 16 -1 (-800 4000)(-625 4000);
WIRE 16 -1 (-800 4050)(-625 4050);
WIRE 16 -1 (-800 4100)(-625 4100);
WIRE 16 -1 (-800 4150)(-625 4150);
WIRE 16 -1 (-800 4200)(-625 4200);
WIRE 16 -1 (-800 4250)(-625 4250);
WIRE 16 -1 (-800 4350)(-625 4350);
WIRE 16 -1 (-2000 3300)(-3100 3300);
FORCEPROP 2 LAST SIG_NAME M_B_CPU1_SB_CS_N<1>
J 0
(-3012 3309);
DISPLAY 0.680851 (-3012 3309);
PAINT WHITE (-3012 3309);
WIRE 16 -1 (-2000 3450)(-3100 3450);
FORCEPROP 2 LAST SIG_NAME M_B_CPU1_SA_CS_N<1>
J 0
(-3012 3459);
DISPLAY 0.680851 (-3012 3459);
PAINT WHITE (-3012 3459);
WIRE 16 -1 (-2000 3400)(-3100 3400);
FORCEPROP 2 LAST SIG_NAME M_B_CPU1_SA_CS_N<0>
J 0
(-3012 3409);
DISPLAY 0.680851 (-3012 3409);
PAINT WHITE (-3012 3409);
WIRE 16 -1 (-2175 2400)(-2000 2400);
WIRE 16 -1 (-2175 2450)(-2000 2450);
WIRE 16 -1 (-2175 2500)(-2000 2500);
WIRE 16 -1 (-2175 2650)(-2000 2650);
WIRE 16 -1 (-2175 2750)(-2000 2750);
WIRE 16 -1 (-2175 2800)(-2000 2800);
WIRE 16 -1 (-2175 2900)(-2000 2900);
WIRE 16 -1 (-2175 2950)(-2000 2950);
WIRE 16 -1 (-2175 4000)(-2000 4000);
WIRE 16 -1 (-2175 4400)(-2000 4400);
WIRE 16 -1 (-2175 3950)(-2000 3950);
WIRE 16 -1 (-2175 4350)(-2000 4350);
WIRE 16 -1 (-2175 3900)(-2000 3900);
WIRE 16 -1 (-2175 4300)(-2000 4300);
WIRE 16 -1 (-2175 3850)(-2000 3850);
WIRE 16 -1 (-2175 4250)(-2000 4250);
WIRE 16 -1 (-2175 3800)(-2000 3800);
WIRE 16 -1 (-2175 4200)(-2000 4200);
WIRE 16 -1 (-2175 3750)(-2000 3750);
WIRE 16 -1 (-2175 4150)(-2000 4150);
WIRE 16 -1 (-2175 3700)(-2000 3700);
WIRE 16 -1 (-2175 4100)(-2000 4100);
WIRE 16 -1 (-2175 2550)(-2000 2550);
WIRE 16 -1 (-2175 2700)(-2000 2700);
WIRE 16 -1 (-2175 3000)(-2000 3000);
WIRE 16 -1 (-800 4400)(-625 4400);
WIRE 16 -1 (-2000 450)(-3100 450);
FORCEPROP 2 LAST SIG_NAME PD_CHB_CPU1_DIMM1_SAA
J 0
(-3012 459);
DISPLAY 0.680851 (-3012 459);
PAINT WHITE (-3012 459);
WIRE 16 -1 (-2000 350)(-2000 450);
WIRE 16 -1 (2150 750)(2150 625);
WIRE 16 -1 (2775 750)(2150 750);
WIRE 16 -1 (2775 625)(2775 750);
WIRE 16 -1 (2150 275)(2150 425);
WIRE 16 -1 (2775 275)(2150 275);
WIRE 16 -1 (2775 275)(2775 425);
DOT 1 (3850 1950);
DOT 1 (5550 1750);
DOT 1 (5550 1050);
DOT 1 (5550 1100);
DOT 1 (5550 1150);
DOT 1 (5550 4350);
DOT 1 (5550 4300);
DOT 1 (5550 4250);
DOT 1 (5550 4200);
DOT 1 (5550 4150);
DOT 1 (5550 4100);
DOT 1 (5550 4050);
DOT 1 (5550 4000);
DOT 1 (5550 3950);
DOT 1 (5550 3900);
DOT 1 (5550 3850);
DOT 1 (5550 3800);
DOT 1 (5550 3750);
DOT 1 (5550 3700);
DOT 1 (5550 3650);
DOT 1 (5550 3600);
DOT 1 (5550 3550);
DOT 1 (5550 3500);
DOT 1 (5550 3450);
DOT 1 (5550 3400);
DOT 1 (5550 3350);
DOT 1 (5550 3300);
DOT 1 (5550 3250);
DOT 1 (5550 3200);
DOT 1 (5550 3150);
DOT 1 (5550 3100);
DOT 1 (5550 3050);
DOT 1 (5550 3000);
DOT 1 (5550 2950);
DOT 1 (5550 2900);
DOT 1 (5550 2850);
DOT 1 (5550 2800);
DOT 1 (5550 2750);
DOT 1 (5550 2700);
DOT 1 (5550 2600);
DOT 1 (5550 2650);
DOT 1 (5550 2550);
DOT 1 (5550 2500);
DOT 1 (5550 2450);
DOT 1 (5550 2400);
DOT 1 (5550 2350);
DOT 1 (5550 2300);
DOT 1 (5550 2250);
DOT 1 (5550 2200);
DOT 1 (5550 2150);
DOT 1 (5550 2100);
DOT 1 (5550 2050);
DOT 1 (5550 2000);
DOT 1 (5550 1950);
DOT 1 (5550 1900);
DOT 1 (5550 1850);
DOT 1 (5550 1800);
DOT 1 (5550 1700);
DOT 1 (5550 1650);
DOT 1 (5550 1600);
DOT 1 (5550 1550);
DOT 1 (5550 1500);
DOT 1 (5550 1450);
DOT 1 (5550 1400);
DOT 1 (5550 1350);
DOT 1 (5550 1300);
DOT 1 (5550 1250);
DOT 1 (3850 4400);
DOT 1 (3850 4150);
DOT 1 (3850 4200);
DOT 1 (3850 4350);
DOT 1 (3850 4100);
DOT 1 (3850 4050);
DOT 1 (3850 4000);
DOT 1 (3850 3950);
DOT 1 (3850 3900);
DOT 1 (3850 3850);
DOT 1 (3850 3800);
DOT 1 (3850 3750);
DOT 1 (3850 3700);
DOT 1 (3850 3650);
DOT 1 (3850 3600);
DOT 1 (3850 3550);
DOT 1 (3850 3500);
DOT 1 (3850 3450);
DOT 1 (3850 3400);
DOT 1 (3850 3350);
DOT 1 (3850 3300);
DOT 1 (3850 3250);
DOT 1 (3850 3200);
DOT 1 (3850 3150);
DOT 1 (3850 3100);
DOT 1 (3850 3050);
DOT 1 (3850 2950);
DOT 1 (3850 2900);
DOT 1 (3850 2800);
DOT 1 (3850 2750);
DOT 1 (3850 2700);
DOT 1 (3850 2600);
DOT 1 (3850 2650);
DOT 1 (3850 2550);
DOT 1 (3850 2450);
DOT 1 (3850 2500);
DOT 1 (3850 2400);
DOT 1 (3850 2350);
DOT 1 (3850 2300);
DOT 1 (3850 2200);
DOT 1 (3850 2250);
DOT 1 (3850 2100);
DOT 1 (3850 2150);
DOT 1 (3850 2050);
DOT 1 (3850 1900);
DOT 1 (3850 1850);
DOT 1 (3850 1800);
DOT 1 (3850 1700);
DOT 1 (3850 1750);
DOT 1 (3850 1650);
DOT 1 (3850 1550);
DOT 1 (3850 1600);
DOT 1 (3850 1500);
DOT 1 (3850 1450);
DOT 1 (3850 1400);
DOT 1 (3850 1350);
DOT 1 (3850 1300);
DOT 1 (3850 1150);
DOT 1 (3850 1200);
DOT 1 (3850 1250);
DOT 1 (2775 275);
DOT 1 (2150 750);
DOT 1 (3850 3000);
DOT 1 (3850 2000);
DOT 1 (3850 2850);
FORCENOTE
20210728 MODIFY FOR GT
(-3425 5050) 0;
DISPLAY LEFT (-3425 5050);
DISPLAY 2.510638 (-3425 5050);
PAINT PINK (-3425 5050);
QUIT
